FILE_TYPE = MACRO_DRAWING;
SET COLOR_WIRE YELLOW;
SET COLOR_PROP ORANGE;
SET COLOR_DOT WHITE;
SET COLOR_ARC YELLOW;
SET COLOR_BODY GREEN;
SET COLOR_NOTE PURPLE;
SET PROP_DISPLAY VALUE;
SET PAGE_NUMBER P255;
FORCEADD UNIVERSAL_GND..1
(1675 1175);
FORCEPROP 3 LASTPIN (1675 1225) SIG_NAME GND\g
J 0
(1685 1235);
DISPLAY 0.659574 (1685 1235);
PAINT MONO (1685 1235);
DISPLAY INVISIBLE (1685 1235);
FORCEPROP 2 LAST CDS_LIB logical_power
J 0
(1675 1175);
PAINT MONO (1675 1175);
DISPLAY INVISIBLE (1675 1175);
FORCEPROP 1 LAST HDL_POWER GND
J 1
(1700 1100);
DISPLAY 0.872340 (1700 1100);
PAINT GREEN (1700 1100);
DISPLAY INVISIBLE (1700 1100);
FORCEPROP 1 LAST PATH I1
J 0
(1750 1175);
DISPLAY 0.872340 (1750 1175);
PAINT AQUA (1750 1175);
DISPLAY INVISIBLE (1750 1175);
FORCEADD UNIVERSAL_GND..1
(2075 2150);
FORCEPROP 3 LASTPIN (2075 2200) SIG_NAME GND\g
J 0
(2085 2210);
DISPLAY 0.659574 (2085 2210);
PAINT MONO (2085 2210);
DISPLAY INVISIBLE (2085 2210);
FORCEPROP 2 LAST CDS_LIB logical_power
J 0
(2075 2150);
PAINT MONO (2075 2150);
DISPLAY INVISIBLE (2075 2150);
FORCEPROP 1 LAST HDL_POWER GND
J 1
(2100 2075);
DISPLAY 0.872340 (2100 2075);
PAINT GREEN (2100 2075);
DISPLAY INVISIBLE (2100 2075);
FORCEPROP 1 LAST PATH I10
J 0
(2150 2150);
DISPLAY 0.872340 (2150 2150);
PAINT AQUA (2150 2150);
DISPLAY INVISIBLE (2150 2150);
FORCEADD Q_CAP..2
(2400 1700);
FORCEPROP 1 LAST PART_NUMBER CH4104K1B00
J 1
(2700 1725);
DISPLAY 0.617021 (2700 1725);
PAINT BLUE (2700 1725);
DISPLAY INVISIBLE (2700 1725);
FORCEPROP 1 LAST PACK_TYPE 0402
J 1
(2850 1700);
DISPLAY 0.617021 (2850 1700);
PAINT SKYBLUE (2850 1700);
FORCEPROP 1 LAST VOLTAGE 25V
J 0
(2725 1700);
DISPLAY 0.617021 (2725 1700);
PAINT SKYBLUE (2725 1700);
FORCEPROP 1 LAST MATERIAL X7R
J 0
(2850 1725);
DISPLAY 0.617021 (2850 1725);
PAINT SKYBLUE (2850 1725);
FORCEPROP 1 LAST TOLERANCE 10%
J 2
(3000 1725);
DISPLAY 0.617021 (3000 1725);
PAINT SKYBLUE (3000 1725);
FORCEPROP 1 LAST VALUE 0.1UF
J 2
(2700 1700);
DISPLAY 0.617021 (2700 1700);
PAINT SKYBLUE (2700 1700);
FORCEPROP 1 LAST LOCATION PC1342
J 1
(2200 1700);
DISPLAY 0.617021 (2200 1700);
PAINT AQUA (2200 1700);
FORCEPROP 1 LASTPIN (2300 1700) $PN 1
J 0
(2290 1715);
DISPLAY 0.617021 (2290 1715);
FORCEPROP 1 LASTPIN (2500 1700) $PN 2
J 0
(2485 1715);
DISPLAY 0.617021 (2485 1715);
FORCEPROP 2 LAST CDS_LIB pure_quanta
J 0
(2400 1700);
PAINT MONO (2400 1700);
DISPLAY INVISIBLE (2400 1700);
FORCEPROP 1 LAST PATH I11
J 0
(2400 1900);
DISPLAY 0.978723 (2400 1900);
PAINT WHITE (2400 1900);
DISPLAY INVISIBLE (2400 1900);
FORCEPROP 2 LAST $SEC 1
J 0
(2400 1950);
DISPLAY 0.680851 (2400 1950);
PAINT MONO (2400 1950);
DISPLAY INVISIBLE (2400 1950);
FORCEPROP 2 LAST CDS_SEC 1
J 0
(2400 1950);
DISPLAY 1.021277 (2400 1950);
DISPLAY INVISIBLE (2400 1950);
FORCEADD ISL99390FRZTR5935..1
(3600 1900);
FORCEPROP 1 LAST PART_NUMBER AL099390004
J 0
(3300 2700);
DISPLAY 0.617021 (3300 2700);
PAINT BLUE (3300 2700);
DISPLAY INVISIBLE (3300 2700);
FORCEPROP 2 LAST PART_TYPE SMLF
J 0
(3300 2900);
DISPLAY 0.638298 (3300 2900);
FORCEPROP 1 LAST MATERIAL IC
J 0
(3300 2625);
DISPLAY 0.617021 (3300 2625);
PAINT SKYBLUE (3300 2625);
FORCEPROP 2 LAST VALUE ISL99390FRZ-TR5935
J 0
(3300 2850);
DISPLAY 0.617021 (3300 2850);
PAINT SKYBLUE (3300 2850);
FORCEPROP 1 LAST LOCATION PU8_P0_6
J 0
(3300 2775);
DISPLAY 0.617021 (3300 2775);
PAINT AQUA (3300 2775);
FORCEPROP 2 LASTPIN (4000 1450) $PN 2
J 0
(4010 1460);
DISPLAY 0.617021 (4010 1460);
PAINT MONO (4010 1460);
FORCEPROP 2 LASTPIN (4000 2250) $PN 33
J 0
(4010 2260);
DISPLAY 0.617021 (4010 2260);
PAINT MONO (4010 2260);
FORCEPROP 2 LASTPIN (3150 1650) $PN 31
J 2
(3140 1660);
DISPLAY 0.617021 (3140 1660);
PAINT MONO (3140 1660);
FORCEPROP 2 LASTPIN (3150 2050) $PN 35
J 2
(3140 2060);
DISPLAY 0.617021 (3140 2060);
PAINT MONO (3140 2060);
FORCEPROP 2 LASTPIN (4000 1600) $PN 6
J 0
(4010 1610);
DISPLAY 0.617021 (4010 1610);
PAINT MONO (4010 1610);
FORCEPROP 2 LASTPIN (4000 1550) $PN 41
J 0
(4010 1560);
DISPLAY 0.617021 (4010 1560);
PAINT MONO (4010 1560);
FORCEPROP 2 LASTPIN (3150 1900) $PN 38
J 2
(3140 1910);
DISPLAY 0.617021 (3140 1910);
PAINT MONO (3140 1910);
FORCEPROP 2 LASTPIN (3150 1600) $PN 37
J 2
(3140 1610);
DISPLAY 0.617021 (3140 1610);
PAINT MONO (3140 1610);
FORCEPROP 2 LASTPIN (4000 1400) $PN 5
J 0
(4010 1410);
DISPLAY 0.617021 (4010 1410);
PAINT MONO (4010 1410);
FORCEPROP 2 LASTPIN (4000 1350) $PN 7_9-20_24
J 0
(4010 1360);
DISPLAY 0.617021 (4010 1360);
PAINT MONO (4010 1360);
FORCEPROP 2 LASTPIN (4000 1300) $PN 40
J 0
(4010 1310);
DISPLAY 0.617021 (4010 1310);
PAINT MONO (4010 1310);
FORCEPROP 2 LASTPIN (4000 2000) $PN 32
J 0
(4010 2010);
DISPLAY 0.617021 (4010 2010);
PAINT MONO (4010 2010);
FORCEPROP 2 LASTPIN (3150 2550) $PN 4
J 2
(3140 2560);
DISPLAY 0.617021 (3140 2560);
PAINT MONO (3140 2560);
FORCEPROP 2 LASTPIN (3150 1300) $PN 34
J 2
(3140 1310);
DISPLAY 0.617021 (3140 1310);
PAINT MONO (3140 1310);
FORCEPROP 2 LASTPIN (3150 1800) $PN 39
J 2
(3140 1810);
DISPLAY 0.617021 (3140 1810);
PAINT MONO (3140 1810);
FORCEPROP 2 LASTPIN (4000 1900) $PN 10_19
J 0
(4010 1910);
DISPLAY 0.617021 (4010 1910);
PAINT MONO (4010 1910);
FORCEPROP 2 LASTPIN (3150 1400) $PN 36
J 2
(3140 1410);
DISPLAY 0.617021 (3140 1410);
PAINT MONO (3140 1410);
FORCEPROP 2 LASTPIN (3150 2250) $PN 3
J 2
(3140 2260);
DISPLAY 0.617021 (3140 2260);
PAINT MONO (3140 2260);
FORCEPROP 2 LASTPIN (4000 2550) $PN 25_29
J 0
(4010 2560);
DISPLAY 0.617021 (4010 2560);
PAINT MONO (4010 2560);
FORCEPROP 2 LASTPIN (4000 2500) $PN 30
J 0
(4010 2510);
DISPLAY 0.617021 (4010 2510);
PAINT MONO (4010 2510);
FORCEPROP 2 LASTPIN (4000 1650) $PN 1
J 0
(4010 1660);
DISPLAY 0.617021 (4010 1660);
PAINT MONO (4010 1660);
FORCEPROP 1 LAST NEEDS_NO_SIZE TRUE
J 0
(3600 1900);
DISPLAY 0.723404 (3600 1900);
PAINT GREEN (3600 1900);
DISPLAY INVISIBLE (3600 1900);
FORCEPROP 1 LAST CDS_LMAN_SYM_OUTLINE -300,700,250,-650
J 0
(3600 1900);
DISPLAY 0.468085 (3600 1900);
PAINT GREEN (3600 1900);
DISPLAY INVISIBLE (3600 1900);
FORCEPROP 2 LAST CDS_LIB pure_quanta
J 0
(3600 1900);
DISPLAY INVISIBLE (3600 1900);
FORCEPROP 2 LAST SEC_TYPE 
J 0
(3300 2825);
DISPLAY 1.021277 (3300 2825);
DISPLAY INVISIBLE (3300 2825);
FORCEPROP 1 LAST PATH I12
J 0
(3600 1900);
DISPLAY 0.723404 (3600 1900);
PAINT GREEN (3600 1900);
DISPLAY INVISIBLE (3600 1900);
FORCEPROP 2 LAST SEC 1
J 0
(3300 2825);
DISPLAY 0.680851 (3300 2825);
PAINT MONO (3300 2825);
DISPLAY INVISIBLE (3300 2825);
FORCEADD Q_CAP..1
(2075 2400);
FORCEPROP 1 LAST PART_NUMBER CH5222KEB01
J 0
(2125 2225);
DISPLAY 0.617021 (2125 2225);
PAINT BLUE (2125 2225);
DISPLAY INVISIBLE (2125 2225);
FORCEPROP 1 LAST MATERIAL X6S
J 0
(2125 2325);
DISPLAY 0.617021 (2125 2325);
PAINT SKYBLUE (2125 2325);
FORCEPROP 1 LAST TOLERANCE 10%
J 0
(2125 2375);
DISPLAY 0.617021 (2125 2375);
PAINT SKYBLUE (2125 2375);
FORCEPROP 1 LAST VALUE 2.2UF
J 0
(2125 2475);
DISPLAY 0.617021 (2125 2475);
PAINT SKYBLUE (2125 2475);
FORCEPROP 1 LAST VOLTAGE 10V
J 0
(2125 2425);
DISPLAY 0.617021 (2125 2425);
PAINT SKYBLUE (2125 2425);
FORCEPROP 1 LAST PACK_TYPE C0402
J 0
(2125 2275);
DISPLAY 0.617021 (2125 2275);
PAINT SKYBLUE (2125 2275);
FORCEPROP 1 LAST LOCATION PC248
J 0
(2125 2525);
DISPLAY 0.617021 (2125 2525);
PAINT AQUA (2125 2525);
FORCEPROP 1 LASTPIN (2075 2500) $PN 1
J 0
(2085 2480);
DISPLAY 0.617021 (2085 2480);
PAINT MONO (2085 2480);
FORCEPROP 1 LASTPIN (2075 2300) $PN 2
J 0
(2085 2280);
DISPLAY 0.617021 (2085 2280);
PAINT MONO (2085 2280);
FORCEPROP 2 LAST CDS_LIB pure_quanta
J 0
(2075 2400);
DISPLAY INVISIBLE (2075 2400);
FORCEPROP 1 LAST PATH I13
J 0
(2125 2550);
DISPLAY 0.978723 (2125 2550);
PAINT WHITE (2125 2550);
DISPLAY INVISIBLE (2125 2550);
FORCEPROP 1 LAST LOCATION PC248
J 0
(2125 2575);
DISPLAY 1.021277 (2125 2575);
PAINT AQUA (2125 2575);
DISPLAY INVISIBLE (2125 2575);
FORCEPROP 0 LAST $SEC 1
J 0
(2125 2575);
DISPLAY 0.680851 (2125 2575);
PAINT MONO (2125 2575);
DISPLAY INVISIBLE (2125 2575);
FORCEPROP 0 LAST CDS_SEC 1
J 0
(2125 2575);
DISPLAY 1.021277 (2125 2575);
DISPLAY INVISIBLE (2125 2575);
FORCEADD Q_RES..2
(2075 2900);
FORCEPROP 1 LAST PART_NUMBER CS-2202FB01
J 0
(2115 2775);
DISPLAY 0.617021 (2115 2775);
PAINT BLUE (2115 2775);
DISPLAY INVISIBLE (2115 2775);
FORCEPROP 1 LAST WATTAGE 1/16W
J 0
(2115 2875);
DISPLAY 0.617021 (2115 2875);
PAINT SKYBLUE (2115 2875);
FORCEPROP 1 LAST MATERIAL CHIP
J 0
(2115 2825);
DISPLAY 0.617021 (2115 2825);
PAINT SKYBLUE (2115 2825);
FORCEPROP 1 LAST TOLERANCE 1%
J 0
(2120 2925);
DISPLAY 0.617021 (2120 2925);
PAINT SKYBLUE (2120 2925);
FORCEPROP 1 LAST VALUE 2.2
J 0
(2120 2975);
DISPLAY 0.617021 (2120 2975);
PAINT SKYBLUE (2120 2975);
FORCEPROP 1 LAST PACK_TYPE 0402LF
J 0
(2115 2725);
DISPLAY 0.617021 (2115 2725);
PAINT SKYBLUE (2115 2725);
FORCEPROP 1 LAST LOCATION PR140
J 0
(2120 3025);
DISPLAY 0.617021 (2120 3025);
PAINT AQUA (2120 3025);
FORCEPROP 1 LASTPIN (2075 3000) $PN 1
J 0
(2080 2962);
DISPLAY 0.617021 (2080 2962);
PAINT MONO (2080 2962);
FORCEPROP 1 LASTPIN (2075 2800) $PN 2
J 0
(2080 2810);
DISPLAY 0.617021 (2080 2810);
PAINT MONO (2080 2810);
FORCEPROP 2 LAST CDS_LIB pure_quanta
J 0
(2075 2900);
DISPLAY INVISIBLE (2075 2900);
FORCEPROP 1 LAST PATH I14
J 0
(2125 3075);
DISPLAY 0.978723 (2125 3075);
PAINT WHITE (2125 3075);
DISPLAY INVISIBLE (2125 3075);
FORCEPROP 1 LAST LOCATION PR140
J 0
(2125 3075);
DISPLAY 1.021277 (2125 3075);
PAINT AQUA (2125 3075);
DISPLAY INVISIBLE (2125 3075);
FORCEPROP 0 LAST $SEC 1
J 0
(2125 3075);
DISPLAY 0.680851 (2125 3075);
PAINT MONO (2125 3075);
DISPLAY INVISIBLE (2125 3075);
FORCEPROP 0 LAST CDS_SEC 1
J 0
(2125 3075);
DISPLAY 1.021277 (2125 3075);
DISPLAY INVISIBLE (2125 3075);
FORCEADD VCC15..1
(2075 3225);
FORCEPROP 3 LASTPIN (2075 3175) SIG_NAME PVCCIN_CPU0_PVCC\g
J 0
(2085 3185);
DISPLAY 0.659574 (2085 3185);
PAINT MONO (2085 3185);
DISPLAY INVISIBLE (2085 3185);
FORCEPROP 1 LAST HDL_POWER PVCCIN_CPU0_PVCC
J 1
(2075 3275);
DISPLAY 0.617021 (2075 3275);
PAINT GREEN (2075 3275);
FORCEPROP 2 LAST CDS_LIB logical_power
J 0
(2075 3225);
DISPLAY INVISIBLE (2075 3225);
FORCEPROP 1 LAST PATH I15
J 0
(2125 3250);
DISPLAY 0.872340 (2125 3250);
PAINT AQUA (2125 3250);
DISPLAY INVISIBLE (2125 3250);
FORCEADD UNIVERSAL_GND..1
(2500 2675);
FORCEPROP 3 LASTPIN (2500 2725) SIG_NAME GND\g
J 0
(2510 2735);
DISPLAY 0.659574 (2510 2735);
PAINT MONO (2510 2735);
DISPLAY INVISIBLE (2510 2735);
FORCEPROP 2 LAST CDS_LIB logical_power
J 0
(2500 2675);
PAINT MONO (2500 2675);
DISPLAY INVISIBLE (2500 2675);
FORCEPROP 1 LAST HDL_POWER GND
J 1
(2525 2600);
DISPLAY 0.872340 (2525 2600);
PAINT GREEN (2525 2600);
DISPLAY INVISIBLE (2525 2600);
FORCEPROP 1 LAST PATH I16
J 0
(2575 2675);
DISPLAY 0.872340 (2575 2675);
PAINT AQUA (2575 2675);
DISPLAY INVISIBLE (2575 2675);
FORCEADD Q_CAP..1
(2500 2900);
FORCEPROP 1 LAST PART_NUMBER CH5222KEB01
J 0
(2550 2775);
DISPLAY 0.617021 (2550 2775);
PAINT BLUE (2550 2775);
DISPLAY INVISIBLE (2550 2775);
FORCEPROP 1 LAST MATERIAL X6S
J 0
(2550 2825);
DISPLAY 0.617021 (2550 2825);
PAINT SKYBLUE (2550 2825);
FORCEPROP 1 LAST TOLERANCE 10%
J 0
(2550 2875);
DISPLAY 0.617021 (2550 2875);
PAINT SKYBLUE (2550 2875);
FORCEPROP 1 LAST VALUE 2.2UF
J 0
(2550 2975);
DISPLAY 0.617021 (2550 2975);
PAINT SKYBLUE (2550 2975);
FORCEPROP 1 LAST VOLTAGE 10V
J 0
(2550 2925);
DISPLAY 0.617021 (2550 2925);
PAINT SKYBLUE (2550 2925);
FORCEPROP 1 LAST PACK_TYPE C0402
J 0
(2550 2725);
DISPLAY 0.617021 (2550 2725);
PAINT SKYBLUE (2550 2725);
FORCEPROP 1 LASTPIN (2500 3000) $PN 1
J 0
(2510 2980);
DISPLAY 0.617021 (2510 2980);
PAINT MONO (2510 2980);
FORCEPROP 1 LASTPIN (2500 2800) $PN 2
J 0
(2510 2780);
DISPLAY 0.617021 (2510 2780);
PAINT MONO (2510 2780);
FORCEPROP 1 LAST LOCATION PC250_P0_6
J 0
(2550 3025);
DISPLAY 0.617021 (2550 3025);
PAINT AQUA (2550 3025);
FORCEPROP 2 LAST CDS_LIB pure_quanta
J 0
(2500 2900);
DISPLAY INVISIBLE (2500 2900);
FORCEPROP 1 LAST PATH I17
J 0
(2550 3050);
DISPLAY 0.978723 (2550 3050);
PAINT WHITE (2550 3050);
DISPLAY INVISIBLE (2550 3050);
FORCEPROP 1 LAST LOCATION PC250_P0_6
J 0
(2550 3075);
DISPLAY 1.021277 (2550 3075);
PAINT AQUA (2550 3075);
DISPLAY INVISIBLE (2550 3075);
FORCEPROP 0 LAST $SEC 1
J 0
(2550 3075);
DISPLAY 0.680851 (2550 3075);
PAINT MONO (2550 3075);
DISPLAY INVISIBLE (2550 3075);
FORCEPROP 0 LAST CDS_SEC 1
J 0
(2550 3075);
DISPLAY 1.021277 (2550 3075);
DISPLAY INVISIBLE (2550 3075);
FORCEADD OFFPAGE..5
(2175 4225);
FORCEPROP 2 LAST $XR4 266 
J 0
(1920 4333);
DISPLAY 0.638298 (1920 4333);
PAINT MONO (1920 4333);
FORCEPROP 2 LAST $XR3 270 
J 0
(1920 4297);
DISPLAY 0.638298 (1920 4297);
PAINT MONO (1920 4297);
FORCEPROP 2 LAST $XR2 269 
J 0
(1920 4261);
DISPLAY 0.638298 (1920 4261);
PAINT MONO (1920 4261);
FORCEPROP 2 LAST $XR1 268 
J 0
(1920 4189);
DISPLAY 0.638298 (1920 4189);
PAINT MONO (1920 4189);
FORCEPROP 2 LAST $XR0 267 
J 0
(1920 4225);
DISPLAY 0.638298 (1920 4225);
PAINT MONO (1920 4225);
FORCEPROP 1 LAST COMMENT_BODY TRUE
J 0
(2275 4150);
DISPLAY 0.872340 (2275 4150);
PAINT GREEN (2275 4150);
DISPLAY INVISIBLE (2275 4150);
FORCEPROP 1 LAST OFFPAGE TRUE
J 0
(2500 4100);
DISPLAY 0.872340 (2500 4100);
PAINT GREEN (2500 4100);
DISPLAY INVISIBLE (2500 4100);
FORCEPROP 2 LAST CDS_LIB standard
J 0
(2175 4225);
DISPLAY INVISIBLE (2175 4225);
FORCEPROP 2 LAST PATH I18
J 0
(1925 4375);
DISPLAY 1.021277 (1925 4375);
DISPLAY INVISIBLE (1925 4375);
FORCEADD OFFPAGE..1
(2175 4125);
FORCEPROP 2 LAST $XR0 266 
J 0
(1923 4125);
DISPLAY 0.638298 (1923 4125);
PAINT MONO (1923 4125);
FORCEPROP 1 LAST COMMENT_BODY TRUE
J 0
(2300 4025);
DISPLAY 0.872340 (2300 4025);
PAINT GREEN (2300 4025);
DISPLAY INVISIBLE (2300 4025);
FORCEPROP 1 LAST OFFPAGE TRUE
J 0
(2500 4000);
DISPLAY 0.872340 (2500 4000);
PAINT GREEN (2500 4000);
DISPLAY INVISIBLE (2500 4000);
FORCEPROP 2 LAST CDS_LIB standard
J 0
(2175 4125);
DISPLAY INVISIBLE (2175 4125);
FORCEPROP 2 LAST PATH I19
J 0
(1925 4175);
DISPLAY 1.021277 (1925 4175);
DISPLAY INVISIBLE (1925 4175);
FORCEADD Q_RES..2
R 2
(1675 1400);
FORCEPROP 1 LAST PART_NUMBER CS28872FB01
J 2
(1635 1275);
DISPLAY 0.617021 (1635 1275);
PAINT BLUE (1635 1275);
DISPLAY INVISIBLE (1635 1275);
FORCEPROP 1 LAST WATTAGE 1/16W
J 2
(1635 1375);
DISPLAY 0.617021 (1635 1375);
PAINT SKYBLUE (1635 1375);
FORCEPROP 1 LAST MATERIAL EMPTY
J 2
(1635 1325);
DISPLAY 0.617021 (1635 1325);
PAINT RED (1635 1325);
FORCEPROP 1 LAST TOLERANCE 1%
J 2
(1630 1425);
DISPLAY 0.617021 (1630 1425);
PAINT SKYBLUE (1630 1425);
FORCEPROP 1 LAST VALUE 8.87K
J 2
(1630 1475);
DISPLAY 0.617021 (1630 1475);
PAINT SKYBLUE (1630 1475);
FORCEPROP 1 LAST PACK_TYPE 0402LF
J 2
(1635 1225);
DISPLAY 0.617021 (1635 1225);
PAINT SKYBLUE (1635 1225);
FORCEPROP 1 LAST LOCATION PR138
J 2
(1630 1525);
DISPLAY 0.617021 (1630 1525);
PAINT AQUA (1630 1525);
FORCEPROP 1 LASTPIN (1675 1500) $PN 1
J 2
(1670 1462);
DISPLAY 0.617021 (1670 1462);
PAINT MONO (1670 1462);
FORCEPROP 1 LASTPIN (1675 1300) $PN 2
J 2
(1670 1310);
DISPLAY 0.617021 (1670 1310);
PAINT MONO (1670 1310);
FORCEPROP 2 LAST CDS_LIB pure_quanta
J 2
(1675 1400);
DISPLAY INVISIBLE (1675 1400);
FORCEPROP 1 LAST PATH I2
J 2
(1625 1575);
DISPLAY 0.978723 (1625 1575);
PAINT WHITE (1625 1575);
DISPLAY INVISIBLE (1625 1575);
FORCEPROP 0 LAST $SEC 1
J 0
(1650 1575);
DISPLAY 0.680851 (1650 1575);
PAINT MONO (1650 1575);
DISPLAY INVISIBLE (1650 1575);
FORCEPROP 0 LAST CDS_SEC 1
J 0
(1650 1575);
DISPLAY 1.021277 (1650 1575);
DISPLAY INVISIBLE (1650 1575);
FORCEADD UNIVERSAL_GND..1
(1600 4450);
FORCEPROP 3 LASTPIN (1600 4500) SIG_NAME GND\g
J 0
(1610 4510);
DISPLAY 0.659574 (1610 4510);
PAINT MONO (1610 4510);
DISPLAY INVISIBLE (1610 4510);
FORCEPROP 2 LAST CDS_LIB logical_power
J 0
(1600 4450);
PAINT MONO (1600 4450);
DISPLAY INVISIBLE (1600 4450);
FORCEPROP 1 LAST HDL_POWER GND
J 1
(1625 4375);
DISPLAY 0.872340 (1625 4375);
PAINT GREEN (1625 4375);
DISPLAY INVISIBLE (1625 4375);
FORCEPROP 1 LAST PATH I20
J 0
(1675 4450);
DISPLAY 0.872340 (1675 4450);
PAINT AQUA (1675 4450);
DISPLAY INVISIBLE (1675 4450);
FORCEADD OFFPAGE..5
(2175 4725);
FORCEPROP 2 LAST $XR0 266 
J 0
(1920 4725);
DISPLAY 0.638298 (1920 4725);
PAINT MONO (1920 4725);
FORCEPROP 1 LAST COMMENT_BODY TRUE
J 0
(2275 4650);
DISPLAY 0.872340 (2275 4650);
PAINT GREEN (2275 4650);
DISPLAY INVISIBLE (2275 4650);
FORCEPROP 1 LAST OFFPAGE TRUE
J 0
(2500 4600);
DISPLAY 0.872340 (2500 4600);
PAINT GREEN (2500 4600);
DISPLAY INVISIBLE (2500 4600);
FORCEPROP 2 LAST CDS_LIB standard
J 0
(2175 4725);
DISPLAY INVISIBLE (2175 4725);
FORCEPROP 2 LAST PATH I21
J 0
(1925 4775);
DISPLAY 1.021277 (1925 4775);
DISPLAY INVISIBLE (1925 4775);
FORCEADD OFFPAGE..1
(2175 4625);
FORCEPROP 2 LAST $XR6 272 
J 0
(1203 4625);
DISPLAY 0.638298 (1203 4625);
PAINT MONO (1203 4625);
FORCEPROP 2 LAST $XR5 271 
J 0
(1323 4625);
DISPLAY 0.638298 (1323 4625);
PAINT MONO (1323 4625);
FORCEPROP 2 LAST $XR4 270 
J 0
(1443 4625);
DISPLAY 0.638298 (1443 4625);
PAINT MONO (1443 4625);
FORCEPROP 2 LAST $XR3 269 
J 0
(1563 4625);
DISPLAY 0.638298 (1563 4625);
PAINT MONO (1563 4625);
FORCEPROP 2 LAST $XR2 268 
J 0
(1683 4625);
DISPLAY 0.638298 (1683 4625);
PAINT MONO (1683 4625);
FORCEPROP 2 LAST $XR1 267 
J 0
(1803 4625);
DISPLAY 0.638298 (1803 4625);
PAINT MONO (1803 4625);
FORCEPROP 2 LAST $XR0 266 
J 0
(1923 4625);
DISPLAY 0.638298 (1923 4625);
PAINT MONO (1923 4625);
FORCEPROP 1 LAST COMMENT_BODY TRUE
J 0
(2300 4525);
DISPLAY 0.872340 (2300 4525);
PAINT GREEN (2300 4525);
DISPLAY INVISIBLE (2300 4525);
FORCEPROP 1 LAST OFFPAGE TRUE
J 0
(2500 4500);
DISPLAY 0.872340 (2500 4500);
PAINT GREEN (2500 4500);
DISPLAY INVISIBLE (2500 4500);
FORCEPROP 2 LAST CDS_LIB standard
J 0
(2175 4625);
DISPLAY INVISIBLE (2175 4625);
FORCEPROP 2 LAST PATH I22
J 0
(1925 4675);
DISPLAY 1.021277 (1925 4675);
DISPLAY INVISIBLE (1925 4675);
FORCEADD UNIVERSAL_GND..1
(2100 4975);
FORCEPROP 3 LASTPIN (2100 5025) SIG_NAME GND\g
J 0
(2110 5035);
DISPLAY 0.659574 (2110 5035);
PAINT MONO (2110 5035);
DISPLAY INVISIBLE (2110 5035);
FORCEPROP 2 LAST CDS_LIB logical_power
J 0
(2100 4975);
PAINT MONO (2100 4975);
DISPLAY INVISIBLE (2100 4975);
FORCEPROP 1 LAST HDL_POWER GND
J 1
(2125 4900);
DISPLAY 0.872340 (2125 4900);
PAINT GREEN (2125 4900);
DISPLAY INVISIBLE (2125 4900);
FORCEPROP 1 LAST PATH I23
J 0
(2175 4975);
DISPLAY 0.872340 (2175 4975);
PAINT AQUA (2175 4975);
DISPLAY INVISIBLE (2175 4975);
FORCEADD Q_CAP..1
(2100 5225);
FORCEPROP 1 LAST PART_NUMBER CH5222KEB01
J 0
(2150 5050);
DISPLAY 0.617021 (2150 5050);
PAINT BLUE (2150 5050);
DISPLAY INVISIBLE (2150 5050);
FORCEPROP 1 LAST MATERIAL X6S
J 0
(2150 5150);
DISPLAY 0.617021 (2150 5150);
PAINT SKYBLUE (2150 5150);
FORCEPROP 1 LAST TOLERANCE 10%
J 0
(2150 5200);
DISPLAY 0.617021 (2150 5200);
PAINT SKYBLUE (2150 5200);
FORCEPROP 1 LAST VALUE 2.2UF
J 0
(2150 5300);
DISPLAY 0.617021 (2150 5300);
PAINT SKYBLUE (2150 5300);
FORCEPROP 1 LAST VOLTAGE 10V
J 0
(2150 5250);
DISPLAY 0.617021 (2150 5250);
PAINT SKYBLUE (2150 5250);
FORCEPROP 1 LAST PACK_TYPE C0402
J 0
(2150 5100);
DISPLAY 0.617021 (2150 5100);
PAINT SKYBLUE (2150 5100);
FORCEPROP 1 LAST LOCATION PC249
J 0
(2150 5350);
DISPLAY 0.617021 (2150 5350);
PAINT AQUA (2150 5350);
FORCEPROP 1 LASTPIN (2100 5325) $PN 1
J 0
(2110 5305);
DISPLAY 0.617021 (2110 5305);
PAINT MONO (2110 5305);
FORCEPROP 1 LASTPIN (2100 5125) $PN 2
J 0
(2110 5105);
DISPLAY 0.617021 (2110 5105);
PAINT MONO (2110 5105);
FORCEPROP 2 LAST CDS_LIB pure_quanta
J 0
(2100 5225);
DISPLAY INVISIBLE (2100 5225);
FORCEPROP 1 LAST PATH I24
J 0
(2150 5375);
DISPLAY 0.978723 (2150 5375);
PAINT WHITE (2150 5375);
DISPLAY INVISIBLE (2150 5375);
FORCEPROP 1 LAST LOCATION PC249
J 0
(2150 5400);
DISPLAY 1.021277 (2150 5400);
PAINT AQUA (2150 5400);
DISPLAY INVISIBLE (2150 5400);
FORCEPROP 0 LAST $SEC 1
J 0
(2150 5400);
DISPLAY 0.680851 (2150 5400);
PAINT MONO (2150 5400);
DISPLAY INVISIBLE (2150 5400);
FORCEPROP 0 LAST CDS_SEC 1
J 0
(2150 5400);
DISPLAY 1.021277 (2150 5400);
DISPLAY INVISIBLE (2150 5400);
FORCEADD Q_CAP..2
(2425 4525);
FORCEPROP 1 LAST PART_NUMBER CH4104K1B00
J 1
(2725 4550);
DISPLAY 0.617021 (2725 4550);
PAINT BLUE (2725 4550);
DISPLAY INVISIBLE (2725 4550);
FORCEPROP 1 LAST VOLTAGE 25V
J 0
(2750 4525);
DISPLAY 0.617021 (2750 4525);
PAINT SKYBLUE (2750 4525);
FORCEPROP 1 LAST VALUE 0.1UF
J 2
(2725 4525);
DISPLAY 0.617021 (2725 4525);
PAINT SKYBLUE (2725 4525);
FORCEPROP 1 LAST TOLERANCE 10%
J 2
(3025 4550);
DISPLAY 0.617021 (3025 4550);
PAINT SKYBLUE (3025 4550);
FORCEPROP 1 LAST PACK_TYPE 0402
J 1
(2875 4525);
DISPLAY 0.617021 (2875 4525);
PAINT SKYBLUE (2875 4525);
FORCEPROP 1 LAST MATERIAL X7R
J 0
(2875 4550);
DISPLAY 0.617021 (2875 4550);
PAINT SKYBLUE (2875 4550);
FORCEPROP 1 LAST LOCATION PC1343
J 1
(2225 4525);
DISPLAY 0.617021 (2225 4525);
PAINT AQUA (2225 4525);
FORCEPROP 1 LASTPIN (2325 4525) $PN 1
J 0
(2315 4540);
DISPLAY 0.617021 (2315 4540);
FORCEPROP 1 LASTPIN (2525 4525) $PN 2
J 0
(2510 4540);
DISPLAY 0.617021 (2510 4540);
FORCEPROP 2 LAST CDS_LIB pure_quanta
J 0
(2425 4525);
PAINT MONO (2425 4525);
DISPLAY INVISIBLE (2425 4525);
FORCEPROP 1 LAST PATH I25
J 0
(2425 4725);
DISPLAY 0.978723 (2425 4725);
PAINT WHITE (2425 4725);
DISPLAY INVISIBLE (2425 4725);
FORCEPROP 2 LAST $SEC 1
J 0
(2425 4775);
DISPLAY 0.680851 (2425 4775);
PAINT MONO (2425 4775);
DISPLAY INVISIBLE (2425 4775);
FORCEPROP 2 LAST CDS_SEC 1
J 0
(2425 4775);
DISPLAY 1.021277 (2425 4775);
DISPLAY INVISIBLE (2425 4775);
FORCEADD Q_RES..2
(2100 5725);
FORCEPROP 1 LAST PART_NUMBER CS-2202FB01
J 0
(2140 5600);
DISPLAY 0.617021 (2140 5600);
PAINT BLUE (2140 5600);
DISPLAY INVISIBLE (2140 5600);
FORCEPROP 1 LAST WATTAGE 1/16W
J 0
(2140 5700);
DISPLAY 0.617021 (2140 5700);
PAINT SKYBLUE (2140 5700);
FORCEPROP 1 LAST MATERIAL CHIP
J 0
(2140 5650);
DISPLAY 0.617021 (2140 5650);
PAINT SKYBLUE (2140 5650);
FORCEPROP 1 LAST TOLERANCE 1%
J 0
(2145 5750);
DISPLAY 0.617021 (2145 5750);
PAINT SKYBLUE (2145 5750);
FORCEPROP 1 LAST VALUE 2.2
J 0
(2145 5800);
DISPLAY 0.617021 (2145 5800);
PAINT SKYBLUE (2145 5800);
FORCEPROP 1 LAST PACK_TYPE 0402LF
J 0
(2140 5550);
DISPLAY 0.617021 (2140 5550);
PAINT SKYBLUE (2140 5550);
FORCEPROP 1 LAST LOCATION PR141
J 0
(2145 5850);
DISPLAY 0.617021 (2145 5850);
PAINT AQUA (2145 5850);
FORCEPROP 1 LASTPIN (2100 5825) $PN 1
J 0
(2105 5787);
DISPLAY 0.617021 (2105 5787);
PAINT MONO (2105 5787);
FORCEPROP 1 LASTPIN (2100 5625) $PN 2
J 0
(2105 5635);
DISPLAY 0.617021 (2105 5635);
PAINT MONO (2105 5635);
FORCEPROP 2 LAST CDS_LIB pure_quanta
J 0
(2100 5725);
DISPLAY INVISIBLE (2100 5725);
FORCEPROP 1 LAST PATH I26
J 0
(2150 5900);
DISPLAY 0.978723 (2150 5900);
PAINT WHITE (2150 5900);
DISPLAY INVISIBLE (2150 5900);
FORCEPROP 1 LAST LOCATION PR141
J 0
(2150 5900);
DISPLAY 1.021277 (2150 5900);
PAINT AQUA (2150 5900);
DISPLAY INVISIBLE (2150 5900);
FORCEPROP 0 LAST $SEC 1
J 0
(2150 5900);
DISPLAY 0.680851 (2150 5900);
PAINT MONO (2150 5900);
DISPLAY INVISIBLE (2150 5900);
FORCEPROP 0 LAST CDS_SEC 1
J 0
(2150 5900);
DISPLAY 1.021277 (2150 5900);
DISPLAY INVISIBLE (2150 5900);
FORCEADD VCC15..1
(2100 6050);
FORCEPROP 3 LASTPIN (2100 6000) SIG_NAME PVCCIN_CPU0_PVCC\g
J 0
(2110 6010);
DISPLAY 0.659574 (2110 6010);
PAINT MONO (2110 6010);
DISPLAY INVISIBLE (2110 6010);
FORCEPROP 1 LAST HDL_POWER PVCCIN_CPU0_PVCC
J 1
(2100 6100);
DISPLAY 0.617021 (2100 6100);
PAINT GREEN (2100 6100);
FORCEPROP 2 LAST CDS_LIB logical_power
J 0
(2100 6050);
DISPLAY INVISIBLE (2100 6050);
FORCEPROP 1 LAST PATH I27
J 0
(2150 6075);
DISPLAY 0.872340 (2150 6075);
PAINT AQUA (2150 6075);
DISPLAY INVISIBLE (2150 6075);
FORCEADD UNIVERSAL_GND..1
(2525 5500);
FORCEPROP 3 LASTPIN (2525 5550) SIG_NAME GND\g
J 0
(2535 5560);
DISPLAY 0.659574 (2535 5560);
PAINT MONO (2535 5560);
DISPLAY INVISIBLE (2535 5560);
FORCEPROP 2 LAST CDS_LIB logical_power
J 0
(2525 5500);
PAINT MONO (2525 5500);
DISPLAY INVISIBLE (2525 5500);
FORCEPROP 1 LAST HDL_POWER GND
J 1
(2550 5425);
DISPLAY 0.872340 (2550 5425);
PAINT GREEN (2550 5425);
DISPLAY INVISIBLE (2550 5425);
FORCEPROP 1 LAST PATH I28
J 0
(2600 5500);
DISPLAY 0.872340 (2600 5500);
PAINT AQUA (2600 5500);
DISPLAY INVISIBLE (2600 5500);
FORCEADD Q_CAP..1
(2525 5725);
FORCEPROP 1 LAST PART_NUMBER CH5222KEB01
J 0
(2575 5600);
DISPLAY 0.617021 (2575 5600);
PAINT BLUE (2575 5600);
DISPLAY INVISIBLE (2575 5600);
FORCEPROP 1 LAST MATERIAL X6S
J 0
(2575 5650);
DISPLAY 0.617021 (2575 5650);
PAINT SKYBLUE (2575 5650);
FORCEPROP 1 LAST TOLERANCE 10%
J 0
(2575 5700);
DISPLAY 0.617021 (2575 5700);
PAINT SKYBLUE (2575 5700);
FORCEPROP 1 LAST VALUE 2.2UF
J 0
(2575 5800);
DISPLAY 0.617021 (2575 5800);
PAINT SKYBLUE (2575 5800);
FORCEPROP 1 LAST VOLTAGE 10V
J 0
(2575 5750);
DISPLAY 0.617021 (2575 5750);
PAINT SKYBLUE (2575 5750);
FORCEPROP 1 LAST PACK_TYPE C0402
J 0
(2575 5550);
DISPLAY 0.617021 (2575 5550);
PAINT SKYBLUE (2575 5550);
FORCEPROP 1 LAST LOCATION PC251_P0_5
J 0
(2575 5850);
DISPLAY 0.617021 (2575 5850);
PAINT AQUA (2575 5850);
FORCEPROP 1 LASTPIN (2525 5825) $PN 1
J 0
(2535 5805);
DISPLAY 0.617021 (2535 5805);
PAINT MONO (2535 5805);
FORCEPROP 1 LASTPIN (2525 5625) $PN 2
J 0
(2535 5605);
DISPLAY 0.617021 (2535 5605);
PAINT MONO (2535 5605);
FORCEPROP 2 LAST CDS_LIB pure_quanta
J 0
(2525 5725);
DISPLAY INVISIBLE (2525 5725);
FORCEPROP 1 LAST PATH I29
J 0
(2575 5875);
DISPLAY 0.978723 (2575 5875);
PAINT WHITE (2575 5875);
DISPLAY INVISIBLE (2575 5875);
FORCEPROP 1 LAST LOCATION PC251_P0_5
J 0
(2575 5900);
DISPLAY 1.021277 (2575 5900);
PAINT AQUA (2575 5900);
DISPLAY INVISIBLE (2575 5900);
FORCEPROP 0 LAST $SEC 1
J 0
(2575 5900);
DISPLAY 0.680851 (2575 5900);
PAINT MONO (2575 5900);
DISPLAY INVISIBLE (2575 5900);
FORCEPROP 0 LAST CDS_SEC 1
J 0
(2575 5900);
DISPLAY 1.021277 (2575 5900);
DISPLAY INVISIBLE (2575 5900);
FORCEADD UNIVERSAL_GND..1
(1575 1625);
FORCEPROP 3 LASTPIN (1575 1675) SIG_NAME GND\g
J 0
(1585 1685);
DISPLAY 0.659574 (1585 1685);
PAINT MONO (1585 1685);
DISPLAY INVISIBLE (1585 1685);
FORCEPROP 2 LAST CDS_LIB logical_power
J 0
(1575 1625);
PAINT MONO (1575 1625);
DISPLAY INVISIBLE (1575 1625);
FORCEPROP 1 LAST HDL_POWER GND
J 1
(1600 1550);
DISPLAY 0.872340 (1600 1550);
PAINT GREEN (1600 1550);
DISPLAY INVISIBLE (1600 1550);
FORCEPROP 1 LAST PATH I3
J 0
(1650 1625);
DISPLAY 0.872340 (1650 1625);
PAINT AQUA (1650 1625);
DISPLAY INVISIBLE (1650 1625);
FORCEADD UNIVERSAL_GND..1
(4250 1175);
FORCEPROP 3 LASTPIN (4250 1225) SIG_NAME GND\g
J 0
(4260 1235);
DISPLAY 0.659574 (4260 1235);
PAINT MONO (4260 1235);
DISPLAY INVISIBLE (4260 1235);
FORCEPROP 2 LAST CDS_LIB logical_power
J 0
(4250 1175);
PAINT MONO (4250 1175);
DISPLAY INVISIBLE (4250 1175);
FORCEPROP 1 LAST HDL_POWER GND
J 1
(4275 1100);
DISPLAY 0.872340 (4275 1100);
PAINT GREEN (4275 1100);
DISPLAY INVISIBLE (4275 1100);
FORCEPROP 1 LAST PATH I30
J 0
(4325 1175);
DISPLAY 0.872340 (4325 1175);
PAINT AQUA (4325 1175);
DISPLAY INVISIBLE (4325 1175);
FORCEADD OFFPAGE..6
(5000 1650);
FORCEPROP 2 LAST $XR0 270 
J 0
(4720 1650);
DISPLAY 0.638298 (4720 1650);
PAINT MONO (4720 1650);
FORCEPROP 1 LAST COMMENT_BODY TRUE
J 0
(5100 1575);
DISPLAY 0.872340 (5100 1575);
PAINT GREEN (5100 1575);
DISPLAY INVISIBLE (5100 1575);
FORCEPROP 1 LAST OFFPAGE TRUE
J 0
(5325 1525);
DISPLAY 0.872340 (5325 1525);
PAINT GREEN (5325 1525);
DISPLAY INVISIBLE (5325 1525);
FORCEPROP 2 LAST CDS_LIB standard
J 0
(5000 1650);
DISPLAY INVISIBLE (5000 1650);
FORCEPROP 2 LAST PATH I31
J 0
(4725 1700);
DISPLAY 1.021277 (4725 1700);
DISPLAY INVISIBLE (4725 1700);
FORCEADD Q_INDUCTOR4P_14..1
(6025 1775);
FORCEPROP 1 LAST PART_NUMBER CV+15^0TZ04
J 0
(5800 1935);
DISPLAY 0.617021 (5800 1935);
PAINT BLUE (5800 1935);
DISPLAY INVISIBLE (5800 1935);
FORCEPROP 2 LAST VALUE 150NH
J 0
(5800 2075);
DISPLAY 0.617021 (5800 2075);
PAINT SKYBLUE (5800 2075);
FORCEPROP 1 LAST MATERIAL IND
J 0
(5800 1985);
DISPLAY 0.617021 (5800 1985);
PAINT SKYBLUE (5800 1985);
FORCEPROP 2 LAST PART_TYPE SMLF
J 0
(5800 2125);
DISPLAY 1.021277 (5800 2125);
FORCEPROP 1 LAST LOCATION PL9
J 0
(5800 2030);
DISPLAY 0.617021 (5800 2030);
PAINT AQUA (5800 2030);
FORCEPROP 2 LASTPIN (5625 1900) $PN 1
J 2
(5615 1910);
DISPLAY 0.617021 (5615 1910);
PAINT MONO (5615 1910);
FORCEPROP 2 LASTPIN (5625 1650) $PN 2
J 2
(5615 1660);
DISPLAY 0.617021 (5615 1660);
PAINT MONO (5615 1660);
FORCEPROP 2 LASTPIN (6425 1650) $PN 3
J 0
(6435 1660);
DISPLAY 0.617021 (6435 1660);
PAINT MONO (6435 1660);
FORCEPROP 2 LASTPIN (6425 1900) $PN 4
J 0
(6435 1910);
DISPLAY 0.617021 (6435 1910);
PAINT MONO (6435 1910);
FORCEPROP 1 LAST NEEDS_NO_SIZE TRUE
J 0
(6025 1775);
DISPLAY 0.468085 (6025 1775);
PAINT GREEN (6025 1775);
DISPLAY INVISIBLE (6025 1775);
FORCEPROP 2 LAST CDS_LIB pure_quanta
J 0
(6025 1775);
DISPLAY INVISIBLE (6025 1775);
FORCEPROP 2 LAST SEC_TYPE 
J 0
(5800 2175);
DISPLAY 1.021277 (5800 2175);
DISPLAY INVISIBLE (5800 2175);
FORCEPROP 1 LAST PATH I32
J 0
(6225 1930);
DISPLAY 0.723404 (6225 1930);
PAINT GREEN (6225 1930);
DISPLAY INVISIBLE (6225 1930);
FORCEPROP 2 LAST SEC 1
J 0
(5800 2175);
DISPLAY 0.680851 (5800 2175);
PAINT MONO (5800 2175);
DISPLAY INVISIBLE (5800 2175);
FORCEADD Q_CAP..1
R 2
(5575 2175);
FORCEPROP 1 LAST PART_NUMBER CH4106K1B01
J 2
(5525 2100);
DISPLAY 0.617021 (5525 2100);
PAINT BLUE (5525 2100);
DISPLAY INVISIBLE (5525 2100);
FORCEPROP 1 LAST MATERIAL X7R
J 2
(5525 2125);
DISPLAY 0.617021 (5525 2125);
PAINT SKYBLUE (5525 2125);
FORCEPROP 1 LAST TOLERANCE 10%
J 2
(5525 2150);
DISPLAY 0.617021 (5525 2150);
PAINT SKYBLUE (5525 2150);
FORCEPROP 1 LAST VALUE 100NF
J 2
(5525 2200);
DISPLAY 0.617021 (5525 2200);
PAINT SKYBLUE (5525 2200);
FORCEPROP 1 LAST VOLTAGE 50V
J 2
(5525 2175);
DISPLAY 0.617021 (5525 2175);
PAINT SKYBLUE (5525 2175);
FORCEPROP 1 LAST PACK_TYPE C0402
J 2
(5525 2075);
DISPLAY 0.617021 (5525 2075);
PAINT SKYBLUE (5525 2075);
FORCEPROP 1 LAST LOCATION PC256
J 2
(5525 2250);
DISPLAY 0.617021 (5525 2250);
PAINT AQUA (5525 2250);
FORCEPROP 1 LASTPIN (5575 2275) $PN 1
J 2
(5565 2255);
DISPLAY 0.617021 (5565 2255);
FORCEPROP 1 LASTPIN (5575 2075) $PN 2
J 2
(5565 2055);
DISPLAY 0.617021 (5565 2055);
FORCEPROP 2 LAST CDS_LIB pure_quanta
J 2
(5575 2175);
PAINT MONO (5575 2175);
DISPLAY INVISIBLE (5575 2175);
FORCEPROP 1 LAST PATH I33
J 2
(5525 2325);
DISPLAY 0.978723 (5525 2325);
PAINT WHITE (5525 2325);
DISPLAY INVISIBLE (5525 2325);
FORCEPROP 2 LAST $SEC 1
J 0
(5525 2375);
DISPLAY 0.680851 (5525 2375);
PAINT MONO (5525 2375);
DISPLAY INVISIBLE (5525 2375);
FORCEPROP 2 LAST CDS_SEC 1
J 0
(5525 2375);
DISPLAY 1.021277 (5525 2375);
DISPLAY INVISIBLE (5525 2375);
FORCEADD Q_CAP..1
(4400 2800);
FORCEPROP 1 LAST PART_NUMBER TMP_QCH2336K1B12
J 0
(4450 2650);
DISPLAY 0.617021 (4450 2650);
PAINT BLUE (4450 2650);
DISPLAY INVISIBLE (4450 2650);
FORCEPROP 1 LAST MATERIAL X7R
J 0
(4450 2750);
DISPLAY 0.617021 (4450 2750);
PAINT SKYBLUE (4450 2750);
FORCEPROP 1 LAST TOLERANCE 10%
J 0
(4450 2800);
DISPLAY 0.617021 (4450 2800);
PAINT SKYBLUE (4450 2800);
FORCEPROP 1 LAST VALUE 3300PF
J 0
(4450 2900);
DISPLAY 0.617021 (4450 2900);
PAINT SKYBLUE (4450 2900);
FORCEPROP 1 LAST VOLTAGE 50V
J 0
(4450 2850);
DISPLAY 0.617021 (4450 2850);
PAINT SKYBLUE (4450 2850);
FORCEPROP 1 LAST PACK_TYPE 0402
J 0
(4450 2700);
DISPLAY 0.617021 (4450 2700);
PAINT SKYBLUE (4450 2700);
FORCEPROP 1 LAST LOCATION PC252_P0_6
J 0
(4450 2950);
DISPLAY 0.617021 (4450 2950);
PAINT AQUA (4450 2950);
FORCEPROP 1 LASTPIN (4400 2900) $PN 1
J 0
(4410 2880);
DISPLAY 0.617021 (4410 2880);
PAINT MONO (4410 2880);
FORCEPROP 1 LASTPIN (4400 2700) $PN 2
J 0
(4410 2680);
DISPLAY 0.617021 (4410 2680);
PAINT MONO (4410 2680);
FORCEPROP 2 LAST CDS_LIB pure_quanta
J 0
(4400 2800);
DISPLAY INVISIBLE (4400 2800);
FORCEPROP 1 LAST PATH I34
J 0
(4450 2950);
DISPLAY 0.978723 (4450 2950);
PAINT WHITE (4450 2950);
DISPLAY INVISIBLE (4450 2950);
FORCEPROP 1 LAST LOCATION PC252_P0_6
J 0
(4450 3000);
DISPLAY 1.021277 (4450 3000);
PAINT AQUA (4450 3000);
DISPLAY INVISIBLE (4450 3000);
FORCEPROP 0 LAST $SEC 1
J 0
(4450 3000);
DISPLAY 0.680851 (4450 3000);
PAINT MONO (4450 3000);
DISPLAY INVISIBLE (4450 3000);
FORCEPROP 0 LAST CDS_SEC 1
J 0
(4450 3000);
DISPLAY 1.021277 (4450 3000);
DISPLAY INVISIBLE (4450 3000);
FORCEADD Q_RES..1
(4850 2350);
FORCEPROP 1 LAST PART_NUMBER CS-3302FB01
J 0
(4750 2400);
DISPLAY 0.617021 (4750 2400);
PAINT BLUE (4750 2400);
DISPLAY INVISIBLE (4750 2400);
FORCEPROP 1 LAST WATTAGE 1/16W
J 2
(4975 2425);
DISPLAY 0.617021 (4975 2425);
PAINT SKYBLUE (4975 2425);
FORCEPROP 1 LAST TOLERANCE 1%
J 0
(5100 2350);
DISPLAY 0.617021 (5100 2350);
PAINT SKYBLUE (5100 2350);
FORCEPROP 1 LAST MATERIAL CHIP
J 0
(4750 2450);
DISPLAY 0.617021 (4750 2450);
PAINT SKYBLUE (4750 2450);
FORCEPROP 1 LAST VALUE 3.3
J 2
(5075 2350);
DISPLAY 0.617021 (5075 2350);
PAINT SKYBLUE (5075 2350);
FORCEPROP 1 LAST PACK_TYPE 0402LF
J 0
(4750 2425);
DISPLAY 0.617021 (4750 2425);
PAINT SKYBLUE (4750 2425);
FORCEPROP 1 LAST LOCATION PR1770
J 0
(4625 2350);
DISPLAY 0.617021 (4625 2350);
PAINT AQUA (4625 2350);
FORCEPROP 1 LASTPIN (4750 2350) $PN 1
J 0
(4762 2362);
DISPLAY 0.617021 (4762 2362);
FORCEPROP 1 LASTPIN (4950 2350) $PN 2
J 0
(4912 2362);
DISPLAY 0.617021 (4912 2362);
FORCEPROP 2 LAST CDS_LIB pure_quanta
J 0
(4850 2350);
PAINT MONO (4850 2350);
DISPLAY INVISIBLE (4850 2350);
FORCEPROP 1 LAST PATH I35
J 0
(4800 2500);
DISPLAY 0.978723 (4800 2500);
PAINT WHITE (4800 2500);
DISPLAY INVISIBLE (4800 2500);
FORCEPROP 2 LAST $SEC 1
J 0
(4800 2550);
DISPLAY 0.680851 (4800 2550);
PAINT MONO (4800 2550);
DISPLAY INVISIBLE (4800 2550);
FORCEPROP 2 LAST CDS_SEC 1
J 0
(4800 2550);
DISPLAY 1.021277 (4800 2550);
DISPLAY INVISIBLE (4800 2550);
FORCEADD UNIVERSAL_GND..1
(4275 4000);
FORCEPROP 3 LASTPIN (4275 4050) SIG_NAME GND\g
J 0
(4285 4060);
DISPLAY 0.659574 (4285 4060);
PAINT MONO (4285 4060);
DISPLAY INVISIBLE (4285 4060);
FORCEPROP 2 LAST CDS_LIB logical_power
J 0
(4275 4000);
PAINT MONO (4275 4000);
DISPLAY INVISIBLE (4275 4000);
FORCEPROP 1 LAST HDL_POWER GND
J 1
(4300 3925);
DISPLAY 0.872340 (4300 3925);
PAINT GREEN (4300 3925);
DISPLAY INVISIBLE (4300 3925);
FORCEPROP 1 LAST PATH I36
J 0
(4350 4000);
DISPLAY 0.872340 (4350 4000);
PAINT AQUA (4350 4000);
DISPLAY INVISIBLE (4350 4000);
FORCEADD Q_CAP..1
(4800 2800);
FORCEPROP 1 LAST PART_NUMBER CH5103KEB01
J 0
(4850 2650);
DISPLAY 0.617021 (4850 2650);
PAINT BLUE (4850 2650);
DISPLAY INVISIBLE (4850 2650);
FORCEPROP 1 LAST MATERIAL X6S
J 0
(4850 2750);
DISPLAY 0.617021 (4850 2750);
PAINT SKYBLUE (4850 2750);
FORCEPROP 1 LAST TOLERANCE 10%
J 0
(4850 2800);
DISPLAY 0.617021 (4850 2800);
PAINT SKYBLUE (4850 2800);
FORCEPROP 1 LAST VALUE 1UF
J 0
(4850 2900);
DISPLAY 0.617021 (4850 2900);
PAINT SKYBLUE (4850 2900);
FORCEPROP 1 LAST VOLTAGE 16V
J 0
(4850 2850);
DISPLAY 0.617021 (4850 2850);
PAINT SKYBLUE (4850 2850);
FORCEPROP 1 LAST PACK_TYPE C0402
J 0
(4850 2700);
DISPLAY 0.617021 (4850 2700);
PAINT SKYBLUE (4850 2700);
FORCEPROP 1 LAST LOCATION PC254_P0_6
J 0
(4850 2950);
DISPLAY 0.617021 (4850 2950);
PAINT AQUA (4850 2950);
FORCEPROP 1 LASTPIN (4800 2900) $PN 1
J 0
(4810 2880);
DISPLAY 0.617021 (4810 2880);
PAINT MONO (4810 2880);
FORCEPROP 1 LASTPIN (4800 2700) $PN 2
J 0
(4810 2680);
DISPLAY 0.617021 (4810 2680);
PAINT MONO (4810 2680);
FORCEPROP 2 LAST CDS_LIB pure_quanta
J 0
(4800 2800);
DISPLAY INVISIBLE (4800 2800);
FORCEPROP 1 LAST PATH I37
J 0
(4850 2950);
DISPLAY 0.978723 (4850 2950);
PAINT WHITE (4850 2950);
DISPLAY INVISIBLE (4850 2950);
FORCEPROP 1 LAST LOCATION PC254_P0_6
J 0
(4850 3000);
DISPLAY 1.021277 (4850 3000);
PAINT AQUA (4850 3000);
DISPLAY INVISIBLE (4850 3000);
FORCEPROP 0 LAST $SEC 1
J 0
(4850 3000);
DISPLAY 0.680851 (4850 3000);
PAINT MONO (4850 3000);
DISPLAY INVISIBLE (4850 3000);
FORCEPROP 0 LAST CDS_SEC 1
J 0
(4850 3000);
DISPLAY 1.021277 (4850 3000);
DISPLAY INVISIBLE (4850 3000);
FORCEADD Q_CAP..1
(5200 2800);
FORCEPROP 1 LAST PART_NUMBER CH6223MEA01
J 0
(5250 2650);
DISPLAY 0.617021 (5250 2650);
PAINT BLUE (5250 2650);
DISPLAY INVISIBLE (5250 2650);
FORCEPROP 1 LAST MATERIAL X6S
J 0
(5250 2750);
DISPLAY 0.617021 (5250 2750);
PAINT SKYBLUE (5250 2750);
FORCEPROP 1 LAST TOLERANCE 20%
J 0
(5250 2800);
DISPLAY 0.617021 (5250 2800);
PAINT SKYBLUE (5250 2800);
FORCEPROP 1 LAST VALUE 22UF
J 0
(5250 2900);
DISPLAY 0.617021 (5250 2900);
PAINT SKYBLUE (5250 2900);
FORCEPROP 1 LAST VOLTAGE 16V
J 0
(5250 2850);
DISPLAY 0.617021 (5250 2850);
PAINT SKYBLUE (5250 2850);
FORCEPROP 1 LAST PACK_TYPE C0805
J 0
(5250 2700);
DISPLAY 0.617021 (5250 2700);
PAINT SKYBLUE (5250 2700);
FORCEPROP 1 LAST LOCATION PC258_P0_6
J 0
(5250 2950);
DISPLAY 0.617021 (5250 2950);
PAINT AQUA (5250 2950);
FORCEPROP 1 LASTPIN (5200 2900) $PN 1
J 0
(5210 2880);
DISPLAY 0.617021 (5210 2880);
PAINT MONO (5210 2880);
FORCEPROP 1 LASTPIN (5200 2700) $PN 2
J 0
(5210 2680);
DISPLAY 0.617021 (5210 2680);
PAINT MONO (5210 2680);
FORCEPROP 2 LAST CDS_LIB pure_quanta
J 0
(5200 2800);
DISPLAY INVISIBLE (5200 2800);
FORCEPROP 1 LAST PATH I38
J 0
(5250 2950);
DISPLAY 0.978723 (5250 2950);
PAINT WHITE (5250 2950);
DISPLAY INVISIBLE (5250 2950);
FORCEPROP 1 LAST LOCATION PC258_P0_6
J 0
(5250 3000);
DISPLAY 1.021277 (5250 3000);
PAINT AQUA (5250 3000);
DISPLAY INVISIBLE (5250 3000);
FORCEPROP 0 LAST $SEC 1
J 0
(5250 3000);
DISPLAY 0.680851 (5250 3000);
PAINT MONO (5250 3000);
DISPLAY INVISIBLE (5250 3000);
FORCEPROP 0 LAST CDS_SEC 1
J 0
(5250 3000);
DISPLAY 1.021277 (5250 3000);
DISPLAY INVISIBLE (5250 3000);
FORCEADD Q_CAP..1
(5600 2800);
FORCEPROP 1 LAST PART_NUMBER CH6223MEA01
J 0
(5650 2650);
DISPLAY 0.617021 (5650 2650);
PAINT BLUE (5650 2650);
DISPLAY INVISIBLE (5650 2650);
FORCEPROP 1 LAST MATERIAL X6S
J 0
(5650 2750);
DISPLAY 0.617021 (5650 2750);
PAINT SKYBLUE (5650 2750);
FORCEPROP 1 LAST TOLERANCE 20%
J 0
(5650 2800);
DISPLAY 0.617021 (5650 2800);
PAINT SKYBLUE (5650 2800);
FORCEPROP 1 LAST VALUE 22UF
J 0
(5650 2900);
DISPLAY 0.617021 (5650 2900);
PAINT SKYBLUE (5650 2900);
FORCEPROP 1 LAST VOLTAGE 16V
J 0
(5650 2850);
DISPLAY 0.617021 (5650 2850);
PAINT SKYBLUE (5650 2850);
FORCEPROP 1 LAST PACK_TYPE C0805
J 0
(5650 2700);
DISPLAY 0.617021 (5650 2700);
PAINT SKYBLUE (5650 2700);
FORCEPROP 1 LAST LOCATION PC260_P0_6
J 0
(5650 2950);
DISPLAY 0.617021 (5650 2950);
PAINT AQUA (5650 2950);
FORCEPROP 1 LASTPIN (5600 2900) $PN 1
J 0
(5610 2880);
DISPLAY 0.617021 (5610 2880);
PAINT MONO (5610 2880);
FORCEPROP 1 LASTPIN (5600 2700) $PN 2
J 0
(5610 2680);
DISPLAY 0.617021 (5610 2680);
PAINT MONO (5610 2680);
FORCEPROP 2 LAST CDS_LIB pure_quanta
J 0
(5600 2800);
DISPLAY INVISIBLE (5600 2800);
FORCEPROP 1 LAST PATH I39
J 0
(5650 2950);
DISPLAY 0.978723 (5650 2950);
PAINT WHITE (5650 2950);
DISPLAY INVISIBLE (5650 2950);
FORCEPROP 1 LAST LOCATION PC260_P0_6
J 0
(5650 3000);
DISPLAY 1.021277 (5650 3000);
PAINT AQUA (5650 3000);
DISPLAY INVISIBLE (5650 3000);
FORCEPROP 0 LAST $SEC 1
J 0
(5650 3000);
DISPLAY 0.680851 (5650 3000);
PAINT MONO (5650 3000);
DISPLAY INVISIBLE (5650 3000);
FORCEPROP 0 LAST CDS_SEC 1
J 0
(5650 3000);
DISPLAY 1.021277 (5650 3000);
DISPLAY INVISIBLE (5650 3000);
FORCEADD Q_RES..2
R 2
(1700 4225);
FORCEPROP 1 LAST PART_NUMBER CS28872FB01
J 2
(1660 4100);
DISPLAY 0.617021 (1660 4100);
PAINT BLUE (1660 4100);
DISPLAY INVISIBLE (1660 4100);
FORCEPROP 1 LAST WATTAGE 1/16W
J 2
(1660 4200);
DISPLAY 0.617021 (1660 4200);
PAINT SKYBLUE (1660 4200);
FORCEPROP 1 LAST MATERIAL EMPTY
J 2
(1660 4150);
DISPLAY 0.617021 (1660 4150);
PAINT RED (1660 4150);
FORCEPROP 1 LAST TOLERANCE 1%
J 2
(1655 4250);
DISPLAY 0.617021 (1655 4250);
PAINT SKYBLUE (1655 4250);
FORCEPROP 1 LAST VALUE 8.87K
J 2
(1655 4300);
DISPLAY 0.617021 (1655 4300);
PAINT SKYBLUE (1655 4300);
FORCEPROP 1 LAST PACK_TYPE 0402LF
J 2
(1660 4050);
DISPLAY 0.617021 (1660 4050);
PAINT SKYBLUE (1660 4050);
FORCEPROP 1 LAST LOCATION PR139
J 2
(1655 4350);
DISPLAY 0.617021 (1655 4350);
PAINT AQUA (1655 4350);
FORCEPROP 1 LASTPIN (1700 4325) $PN 1
J 2
(1695 4287);
DISPLAY 0.617021 (1695 4287);
PAINT MONO (1695 4287);
FORCEPROP 1 LASTPIN (1700 4125) $PN 2
J 2
(1695 4135);
DISPLAY 0.617021 (1695 4135);
PAINT MONO (1695 4135);
FORCEPROP 2 LAST CDS_LIB pure_quanta
J 2
(1700 4225);
DISPLAY INVISIBLE (1700 4225);
FORCEPROP 1 LAST PATH I4
J 2
(1650 4400);
DISPLAY 0.978723 (1650 4400);
PAINT WHITE (1650 4400);
DISPLAY INVISIBLE (1650 4400);
FORCEPROP 0 LAST $SEC 1
J 0
(1675 4400);
DISPLAY 0.680851 (1675 4400);
PAINT MONO (1675 4400);
DISPLAY INVISIBLE (1675 4400);
FORCEPROP 0 LAST CDS_SEC 1
J 0
(1675 4400);
DISPLAY 1.021277 (1675 4400);
DISPLAY INVISIBLE (1675 4400);
FORCEADD Q_RES..1
(6125 1375);
FORCEPROP 1 LAST PART_NUMBER CS00002JB13
J 0
(6000 1425);
DISPLAY 0.617021 (6000 1425);
PAINT BLUE (6000 1425);
DISPLAY INVISIBLE (6000 1425);
FORCEPROP 1 LAST WATTAGE 1/16W
J 2
(6375 1475);
DISPLAY 0.617021 (6375 1475);
PAINT SKYBLUE (6375 1475);
FORCEPROP 1 LAST MATERIAL CHIP
J 0
(6400 1375);
DISPLAY 0.617021 (6400 1375);
PAINT SKYBLUE (6400 1375);
FORCEPROP 1 LAST TOLERANCE 5%
J 0
(6325 1375);
DISPLAY 0.617021 (6325 1375);
PAINT SKYBLUE (6325 1375);
FORCEPROP 1 LAST VALUE 0
J 2
(6300 1375);
DISPLAY 0.617021 (6300 1375);
PAINT SKYBLUE (6300 1375);
FORCEPROP 1 LAST PACK_TYPE 0402LF
J 0
(6000 1475);
DISPLAY 0.617021 (6000 1475);
PAINT SKYBLUE (6000 1475);
FORCEPROP 1 LAST LOCATION PR142
J 0
(5850 1375);
DISPLAY 0.617021 (5850 1375);
PAINT AQUA (5850 1375);
FORCEPROP 1 LASTPIN (6025 1375) $PN 1
J 0
(6037 1387);
DISPLAY 0.617021 (6037 1387);
PAINT MONO (6037 1387);
FORCEPROP 1 LASTPIN (6225 1375) $PN 2
J 0
(6187 1387);
DISPLAY 0.617021 (6187 1387);
PAINT MONO (6187 1387);
FORCEPROP 2 LAST CDS_LIB pure_quanta
J 0
(6125 1375);
DISPLAY INVISIBLE (6125 1375);
FORCEPROP 1 LAST PATH I40
J 0
(6075 1525);
DISPLAY 0.978723 (6075 1525);
PAINT WHITE (6075 1525);
DISPLAY INVISIBLE (6075 1525);
FORCEPROP 0 LAST $SEC 1
J 0
(6375 1525);
DISPLAY 0.680851 (6375 1525);
PAINT MONO (6375 1525);
DISPLAY INVISIBLE (6375 1525);
FORCEPROP 0 LAST CDS_SEC 1
J 0
(6375 1525);
DISPLAY 1.021277 (6375 1525);
DISPLAY INVISIBLE (6375 1525);
FORCEADD OFFPAGE..3
(6975 1650);
FORCEPROP 2 LAST $XR0 267 
J 0
(7189 1650);
DISPLAY 0.638298 (7189 1650);
PAINT MONO (7189 1650);
FORCEPROP 2 LAST CDS_LIB standard
J 0
(6975 1650);
DISPLAY INVISIBLE (6975 1650);
FORCEPROP 1 LAST OFFPAGE TRUE
J 0
(7300 1525);
DISPLAY 0.872340 (7300 1525);
PAINT GREEN (7300 1525);
DISPLAY INVISIBLE (7300 1525);
FORCEPROP 1 LAST COMMENT_BODY TRUE
J 0
(6925 1550);
DISPLAY 0.872340 (6925 1550);
PAINT GREEN (6925 1550);
DISPLAY INVISIBLE (6925 1550);
FORCEPROP 2 LAST PATH I41
J 0
(7200 1700);
DISPLAY 1.021277 (7200 1700);
DISPLAY INVISIBLE (7200 1700);
FORCEADD Q_CAP..1
(7725 1700);
FORCEPROP 1 LAST PART_NUMBER CH622KMEA03
J 0
(7775 1525);
DISPLAY 0.617021 (7775 1525);
PAINT BLUE (7775 1525);
DISPLAY INVISIBLE (7775 1525);
FORCEPROP 1 LAST PACK_TYPE C0805
J 0
(7775 1575);
DISPLAY 0.617021 (7775 1575);
PAINT SKYBLUE (7775 1575);
FORCEPROP 1 LAST VOLTAGE 4V
J 0
(7775 1725);
DISPLAY 0.617021 (7775 1725);
PAINT SKYBLUE (7775 1725);
FORCEPROP 1 LAST VALUE 22UF
J 0
(7775 1775);
DISPLAY 0.617021 (7775 1775);
PAINT SKYBLUE (7775 1775);
FORCEPROP 1 LAST TOLERANCE 20%
J 0
(7775 1675);
DISPLAY 0.617021 (7775 1675);
PAINT SKYBLUE (7775 1675);
FORCEPROP 1 LAST MATERIAL X6S
J 0
(7775 1625);
DISPLAY 0.617021 (7775 1625);
PAINT SKYBLUE (7775 1625);
FORCEPROP 1 LAST LOCATION PC266_P0_6
J 0
(7775 1825);
DISPLAY 0.617021 (7775 1825);
PAINT AQUA (7775 1825);
FORCEPROP 1 LASTPIN (7725 1800) $PN 1
J 0
(7735 1780);
DISPLAY 0.617021 (7735 1780);
PAINT MONO (7735 1780);
FORCEPROP 1 LASTPIN (7725 1600) $PN 2
J 0
(7735 1580);
DISPLAY 0.617021 (7735 1580);
PAINT MONO (7735 1580);
FORCEPROP 2 LAST CDS_LIB pure_quanta
J 0
(7725 1700);
DISPLAY INVISIBLE (7725 1700);
FORCEPROP 1 LAST PATH I42
J 0
(7775 1850);
DISPLAY 0.978723 (7775 1850);
PAINT WHITE (7775 1850);
DISPLAY INVISIBLE (7775 1850);
FORCEPROP 1 LAST LOCATION PC266_P0_6
J 0
(7775 1875);
DISPLAY 1.021277 (7775 1875);
PAINT AQUA (7775 1875);
DISPLAY INVISIBLE (7775 1875);
FORCEPROP 0 LAST $SEC 1
J 0
(7775 1875);
DISPLAY 0.680851 (7775 1875);
PAINT MONO (7775 1875);
DISPLAY INVISIBLE (7775 1875);
FORCEPROP 0 LAST CDS_SEC 1
J 0
(7775 1875);
DISPLAY 1.021277 (7775 1875);
DISPLAY INVISIBLE (7775 1875);
FORCEADD Q_CAP..1
(5975 2800);
FORCEPROP 1 LAST PART_NUMBER CH6223MEA01
J 0
(6025 2650);
DISPLAY 0.617021 (6025 2650);
PAINT BLUE (6025 2650);
DISPLAY INVISIBLE (6025 2650);
FORCEPROP 1 LAST MATERIAL X6S
J 0
(6025 2750);
DISPLAY 0.617021 (6025 2750);
PAINT SKYBLUE (6025 2750);
FORCEPROP 1 LAST TOLERANCE 20%
J 0
(6025 2800);
DISPLAY 0.617021 (6025 2800);
PAINT SKYBLUE (6025 2800);
FORCEPROP 1 LAST VALUE 22UF
J 0
(6025 2900);
DISPLAY 0.617021 (6025 2900);
PAINT SKYBLUE (6025 2900);
FORCEPROP 1 LAST VOLTAGE 16V
J 0
(6025 2850);
DISPLAY 0.617021 (6025 2850);
PAINT SKYBLUE (6025 2850);
FORCEPROP 1 LAST PACK_TYPE C0805
J 0
(6025 2700);
DISPLAY 0.617021 (6025 2700);
PAINT SKYBLUE (6025 2700);
FORCEPROP 1 LAST LOCATION PC262_P0_6
J 0
(6025 2950);
DISPLAY 0.617021 (6025 2950);
PAINT AQUA (6025 2950);
FORCEPROP 1 LASTPIN (5975 2900) $PN 1
J 0
(5985 2880);
DISPLAY 0.617021 (5985 2880);
PAINT MONO (5985 2880);
FORCEPROP 1 LASTPIN (5975 2700) $PN 2
J 0
(5985 2680);
DISPLAY 0.617021 (5985 2680);
PAINT MONO (5985 2680);
FORCEPROP 2 LAST CDS_LIB pure_quanta
J 0
(5975 2800);
DISPLAY INVISIBLE (5975 2800);
FORCEPROP 1 LAST PATH I43
J 0
(6025 2950);
DISPLAY 0.978723 (6025 2950);
PAINT WHITE (6025 2950);
DISPLAY INVISIBLE (6025 2950);
FORCEPROP 1 LAST LOCATION PC262_P0_6
J 0
(6025 3000);
DISPLAY 1.021277 (6025 3000);
PAINT AQUA (6025 3000);
DISPLAY INVISIBLE (6025 3000);
FORCEPROP 0 LAST $SEC 1
J 0
(6025 3000);
DISPLAY 0.680851 (6025 3000);
PAINT MONO (6025 3000);
DISPLAY INVISIBLE (6025 3000);
FORCEPROP 0 LAST CDS_SEC 1
J 0
(6025 3000);
DISPLAY 1.021277 (6025 3000);
DISPLAY INVISIBLE (6025 3000);
FORCEADD UNIVERSAL_GND..1
(6200 2375);
FORCEPROP 3 LASTPIN (6200 2425) SIG_NAME GND\g
J 0
(6210 2435);
DISPLAY 0.659574 (6210 2435);
PAINT MONO (6210 2435);
DISPLAY INVISIBLE (6210 2435);
FORCEPROP 2 LAST CDS_LIB logical_power
J 0
(6200 2375);
PAINT MONO (6200 2375);
DISPLAY INVISIBLE (6200 2375);
FORCEPROP 1 LAST HDL_POWER GND
J 1
(6225 2300);
DISPLAY 0.872340 (6225 2300);
PAINT GREEN (6225 2300);
DISPLAY INVISIBLE (6225 2300);
FORCEPROP 1 LAST PATH I44
J 0
(6275 2375);
DISPLAY 0.872340 (6275 2375);
PAINT AQUA (6275 2375);
DISPLAY INVISIBLE (6275 2375);
FORCEADD VCC15..1
(6200 3175);
FORCEPROP 3 LASTPIN (6200 3125) SIG_NAME SW_P12V_PVCCIN_CPU0_FLT\g
J 0
(6210 3135);
DISPLAY 0.659574 (6210 3135);
PAINT MONO (6210 3135);
DISPLAY INVISIBLE (6210 3135);
FORCEPROP 1 LAST HDL_POWER SW_P12V_PVCCIN_CPU0_FLT
J 1
(6250 3225);
DISPLAY 0.617021 (6250 3225);
PAINT GREEN (6250 3225);
FORCEPROP 2 LAST CDS_LIB logical_power
J 0
(6200 3175);
DISPLAY INVISIBLE (6200 3175);
FORCEPROP 1 LAST PATH I45
J 0
(6250 3200);
DISPLAY 0.872340 (6250 3200);
PAINT AQUA (6250 3200);
DISPLAY INVISIBLE (6250 3200);
FORCEADD Q_RES..1
(6150 4175);
FORCEPROP 1 LAST PART_NUMBER CS00002JB13
J 0
(6025 4225);
DISPLAY 0.617021 (6025 4225);
PAINT BLUE (6025 4225);
DISPLAY INVISIBLE (6025 4225);
FORCEPROP 1 LAST PACK_TYPE 0402LF
J 0
(6025 4275);
DISPLAY 0.617021 (6025 4275);
PAINT SKYBLUE (6025 4275);
FORCEPROP 1 LAST VALUE 0
J 2
(6325 4175);
DISPLAY 0.617021 (6325 4175);
PAINT SKYBLUE (6325 4175);
FORCEPROP 1 LAST MATERIAL CHIP
J 0
(6425 4175);
DISPLAY 0.617021 (6425 4175);
PAINT SKYBLUE (6425 4175);
FORCEPROP 1 LAST TOLERANCE 5%
J 0
(6350 4175);
DISPLAY 0.617021 (6350 4175);
PAINT SKYBLUE (6350 4175);
FORCEPROP 1 LAST WATTAGE 1/16W
J 2
(6400 4275);
DISPLAY 0.617021 (6400 4275);
PAINT SKYBLUE (6400 4275);
FORCEPROP 1 LAST LOCATION PR143
J 0
(5875 4175);
DISPLAY 0.617021 (5875 4175);
PAINT AQUA (5875 4175);
FORCEPROP 1 LASTPIN (6050 4175) $PN 1
J 0
(6062 4187);
DISPLAY 0.617021 (6062 4187);
PAINT MONO (6062 4187);
FORCEPROP 1 LASTPIN (6250 4175) $PN 2
J 0
(6212 4187);
DISPLAY 0.617021 (6212 4187);
PAINT MONO (6212 4187);
FORCEPROP 2 LAST CDS_LIB pure_quanta
J 0
(6150 4175);
DISPLAY INVISIBLE (6150 4175);
FORCEPROP 1 LAST PATH I46
J 0
(6100 4325);
DISPLAY 0.978723 (6100 4325);
PAINT WHITE (6100 4325);
DISPLAY INVISIBLE (6100 4325);
FORCEPROP 0 LAST $SEC 1
J 0
(6400 4325);
DISPLAY 0.680851 (6400 4325);
PAINT MONO (6400 4325);
DISPLAY INVISIBLE (6400 4325);
FORCEPROP 0 LAST CDS_SEC 1
J 0
(6400 4325);
DISPLAY 1.021277 (6400 4325);
DISPLAY INVISIBLE (6400 4325);
FORCEADD OFFPAGE..6
(4825 4475);
FORCEPROP 2 LAST $XR0 268 
J 0
(4515 4475);
DISPLAY 0.638298 (4515 4475);
PAINT MONO (4515 4475);
FORCEPROP 2 LAST CDS_LIB standard
J 0
(4825 4475);
DISPLAY INVISIBLE (4825 4475);
FORCEPROP 1 LAST OFFPAGE TRUE
J 0
(5150 4350);
DISPLAY 0.872340 (5150 4350);
PAINT GREEN (5150 4350);
DISPLAY INVISIBLE (5150 4350);
FORCEPROP 1 LAST COMMENT_BODY TRUE
J 0
(4925 4400);
DISPLAY 0.872340 (4925 4400);
PAINT GREEN (4925 4400);
DISPLAY INVISIBLE (4925 4400);
FORCEPROP 2 LAST PATH I47
J 0
(4525 4525);
DISPLAY 1.021277 (4525 4525);
DISPLAY INVISIBLE (4525 4525);
FORCEADD Q_CAP..1
(4425 5625);
FORCEPROP 1 LAST PART_NUMBER TMP_QCH2336K1B12
J 0
(4475 5475);
DISPLAY 0.617021 (4475 5475);
PAINT BLUE (4475 5475);
DISPLAY INVISIBLE (4475 5475);
FORCEPROP 1 LAST MATERIAL X7R
J 0
(4475 5575);
DISPLAY 0.617021 (4475 5575);
PAINT SKYBLUE (4475 5575);
FORCEPROP 1 LAST TOLERANCE 10%
J 0
(4475 5625);
DISPLAY 0.617021 (4475 5625);
PAINT SKYBLUE (4475 5625);
FORCEPROP 1 LAST VALUE 3300PF
J 0
(4475 5725);
DISPLAY 0.617021 (4475 5725);
PAINT SKYBLUE (4475 5725);
FORCEPROP 1 LAST VOLTAGE 50V
J 0
(4475 5675);
DISPLAY 0.617021 (4475 5675);
PAINT SKYBLUE (4475 5675);
FORCEPROP 1 LAST PACK_TYPE 0402
J 0
(4475 5525);
DISPLAY 0.617021 (4475 5525);
PAINT SKYBLUE (4475 5525);
FORCEPROP 1 LAST LOCATION PC253_P0_5
J 0
(4475 5775);
DISPLAY 0.617021 (4475 5775);
PAINT AQUA (4475 5775);
FORCEPROP 1 LASTPIN (4425 5725) $PN 1
J 0
(4435 5705);
DISPLAY 0.617021 (4435 5705);
PAINT MONO (4435 5705);
FORCEPROP 1 LASTPIN (4425 5525) $PN 2
J 0
(4435 5505);
DISPLAY 0.617021 (4435 5505);
PAINT MONO (4435 5505);
FORCEPROP 2 LAST CDS_LIB pure_quanta
J 0
(4425 5625);
DISPLAY INVISIBLE (4425 5625);
FORCEPROP 1 LAST PATH I48
J 0
(4475 5775);
DISPLAY 0.978723 (4475 5775);
PAINT WHITE (4475 5775);
DISPLAY INVISIBLE (4475 5775);
FORCEPROP 1 LAST LOCATION PC253_P0_5
J 0
(4475 5825);
DISPLAY 1.021277 (4475 5825);
PAINT AQUA (4475 5825);
DISPLAY INVISIBLE (4475 5825);
FORCEPROP 0 LAST $SEC 1
J 0
(4475 5825);
DISPLAY 0.680851 (4475 5825);
PAINT MONO (4475 5825);
DISPLAY INVISIBLE (4475 5825);
FORCEPROP 0 LAST CDS_SEC 1
J 0
(4475 5825);
DISPLAY 1.021277 (4475 5825);
DISPLAY INVISIBLE (4475 5825);
FORCEADD Q_RES..1
(4875 5175);
FORCEPROP 1 LAST PART_NUMBER CS-3302FB01
J 0
(4775 5225);
DISPLAY 0.617021 (4775 5225);
PAINT BLUE (4775 5225);
DISPLAY INVISIBLE (4775 5225);
FORCEPROP 1 LAST VALUE 3.3
J 2
(5125 5175);
DISPLAY 0.617021 (5125 5175);
PAINT SKYBLUE (5125 5175);
FORCEPROP 1 LAST TOLERANCE 1%
J 0
(5150 5175);
DISPLAY 0.617021 (5150 5175);
PAINT SKYBLUE (5150 5175);
FORCEPROP 1 LAST PACK_TYPE 0402LF
J 0
(4775 5250);
DISPLAY 0.617021 (4775 5250);
PAINT SKYBLUE (4775 5250);
FORCEPROP 1 LAST MATERIAL CHIP
J 0
(4775 5275);
DISPLAY 0.617021 (4775 5275);
PAINT SKYBLUE (4775 5275);
FORCEPROP 1 LAST WATTAGE 1/16W
J 2
(5000 5250);
DISPLAY 0.617021 (5000 5250);
PAINT SKYBLUE (5000 5250);
FORCEPROP 1 LAST LOCATION PR1771
J 0
(4625 5175);
DISPLAY 0.617021 (4625 5175);
PAINT AQUA (4625 5175);
FORCEPROP 1 LASTPIN (4775 5175) $PN 1
J 0
(4787 5187);
DISPLAY 0.617021 (4787 5187);
FORCEPROP 1 LASTPIN (4975 5175) $PN 2
J 0
(4937 5187);
DISPLAY 0.617021 (4937 5187);
FORCEPROP 2 LAST CDS_LIB pure_quanta
J 0
(4875 5175);
PAINT MONO (4875 5175);
DISPLAY INVISIBLE (4875 5175);
FORCEPROP 1 LAST PATH I49
J 0
(4825 5325);
DISPLAY 0.978723 (4825 5325);
PAINT WHITE (4825 5325);
DISPLAY INVISIBLE (4825 5325);
FORCEPROP 2 LAST $SEC 1
J 0
(4825 5375);
DISPLAY 0.680851 (4825 5375);
PAINT MONO (4825 5375);
DISPLAY INVISIBLE (4825 5375);
FORCEPROP 2 LAST CDS_SEC 1
J 0
(4825 5375);
DISPLAY 1.021277 (4825 5375);
DISPLAY INVISIBLE (4825 5375);
FORCEADD UNIVERSAL_GND..1
(1700 4000);
FORCEPROP 3 LASTPIN (1700 4050) SIG_NAME GND\g
J 0
(1710 4060);
DISPLAY 0.659574 (1710 4060);
PAINT MONO (1710 4060);
DISPLAY INVISIBLE (1710 4060);
FORCEPROP 2 LAST CDS_LIB logical_power
J 0
(1700 4000);
PAINT MONO (1700 4000);
DISPLAY INVISIBLE (1700 4000);
FORCEPROP 1 LAST HDL_POWER GND
J 1
(1725 3925);
DISPLAY 0.872340 (1725 3925);
PAINT GREEN (1725 3925);
DISPLAY INVISIBLE (1725 3925);
FORCEPROP 1 LAST PATH I5
J 0
(1775 4000);
DISPLAY 0.872340 (1775 4000);
PAINT AQUA (1775 4000);
DISPLAY INVISIBLE (1775 4000);
FORCEADD Q_INDUCTOR4P_14..1
(6075 4600);
FORCEPROP 1 LAST PART_NUMBER CV+15^0TZ04
J 0
(5850 4760);
DISPLAY 0.617021 (5850 4760);
PAINT BLUE (5850 4760);
DISPLAY INVISIBLE (5850 4760);
FORCEPROP 2 LAST VALUE 150NH
J 0
(5850 4900);
DISPLAY 0.617021 (5850 4900);
PAINT SKYBLUE (5850 4900);
FORCEPROP 1 LAST MATERIAL IND
J 0
(5850 4810);
DISPLAY 0.617021 (5850 4810);
PAINT SKYBLUE (5850 4810);
FORCEPROP 2 LAST PART_TYPE SMLF
J 0
(5850 4950);
DISPLAY 1.021277 (5850 4950);
FORCEPROP 1 LAST LOCATION PL10
J 0
(5850 4855);
DISPLAY 0.617021 (5850 4855);
PAINT AQUA (5850 4855);
FORCEPROP 2 LASTPIN (5675 4725) $PN 1
J 2
(5665 4735);
DISPLAY 0.617021 (5665 4735);
PAINT MONO (5665 4735);
FORCEPROP 2 LASTPIN (5675 4475) $PN 2
J 2
(5665 4485);
DISPLAY 0.617021 (5665 4485);
PAINT MONO (5665 4485);
FORCEPROP 2 LASTPIN (6475 4475) $PN 3
J 0
(6485 4485);
DISPLAY 0.617021 (6485 4485);
PAINT MONO (6485 4485);
FORCEPROP 2 LASTPIN (6475 4725) $PN 4
J 0
(6485 4735);
DISPLAY 0.617021 (6485 4735);
PAINT MONO (6485 4735);
FORCEPROP 1 LAST NEEDS_NO_SIZE TRUE
J 0
(6075 4600);
DISPLAY 0.468085 (6075 4600);
PAINT GREEN (6075 4600);
DISPLAY INVISIBLE (6075 4600);
FORCEPROP 2 LAST CDS_LIB pure_quanta
J 0
(6075 4600);
DISPLAY INVISIBLE (6075 4600);
FORCEPROP 2 LAST SEC_TYPE 
J 0
(5850 5000);
DISPLAY 1.021277 (5850 5000);
DISPLAY INVISIBLE (5850 5000);
FORCEPROP 1 LAST PATH I50
J 0
(6275 4755);
DISPLAY 0.723404 (6275 4755);
PAINT GREEN (6275 4755);
DISPLAY INVISIBLE (6275 4755);
FORCEPROP 2 LAST SEC 1
J 0
(5850 5000);
DISPLAY 0.680851 (5850 5000);
PAINT MONO (5850 5000);
DISPLAY INVISIBLE (5850 5000);
FORCEADD Q_CAP..1
R 2
(5600 5000);
FORCEPROP 1 LAST PART_NUMBER CH4106K1B01
J 2
(5550 4925);
DISPLAY 0.617021 (5550 4925);
PAINT BLUE (5550 4925);
DISPLAY INVISIBLE (5550 4925);
FORCEPROP 1 LAST PACK_TYPE C0402
J 2
(5550 4900);
DISPLAY 0.617021 (5550 4900);
PAINT SKYBLUE (5550 4900);
FORCEPROP 1 LAST MATERIAL X7R
J 2
(5550 4950);
DISPLAY 0.617021 (5550 4950);
PAINT SKYBLUE (5550 4950);
FORCEPROP 1 LAST TOLERANCE 10%
J 2
(5550 4975);
DISPLAY 0.617021 (5550 4975);
PAINT SKYBLUE (5550 4975);
FORCEPROP 1 LAST VALUE 100NF
J 2
(5550 5025);
DISPLAY 0.617021 (5550 5025);
PAINT SKYBLUE (5550 5025);
FORCEPROP 1 LAST VOLTAGE 50V
J 2
(5550 5000);
DISPLAY 0.617021 (5550 5000);
PAINT SKYBLUE (5550 5000);
FORCEPROP 1 LAST LOCATION PC257
J 2
(5550 5075);
DISPLAY 0.617021 (5550 5075);
PAINT AQUA (5550 5075);
FORCEPROP 1 LASTPIN (5600 5100) $PN 1
J 2
(5590 5080);
DISPLAY 0.617021 (5590 5080);
FORCEPROP 1 LASTPIN (5600 4900) $PN 2
J 2
(5590 4880);
DISPLAY 0.617021 (5590 4880);
FORCEPROP 2 LAST CDS_LIB pure_quanta
J 2
(5600 5000);
PAINT MONO (5600 5000);
DISPLAY INVISIBLE (5600 5000);
FORCEPROP 1 LAST PATH I51
J 2
(5550 5150);
DISPLAY 0.978723 (5550 5150);
PAINT WHITE (5550 5150);
DISPLAY INVISIBLE (5550 5150);
FORCEPROP 2 LAST $SEC 1
J 0
(5550 5200);
DISPLAY 0.680851 (5550 5200);
PAINT MONO (5550 5200);
DISPLAY INVISIBLE (5550 5200);
FORCEPROP 2 LAST CDS_SEC 1
J 0
(5550 5200);
DISPLAY 1.021277 (5550 5200);
DISPLAY INVISIBLE (5550 5200);
FORCEADD Q_CAP..1
(4825 5625);
FORCEPROP 1 LAST PART_NUMBER CH5103KEB01
J 0
(4875 5475);
DISPLAY 0.617021 (4875 5475);
PAINT BLUE (4875 5475);
DISPLAY INVISIBLE (4875 5475);
FORCEPROP 1 LAST MATERIAL X6S
J 0
(4875 5575);
DISPLAY 0.617021 (4875 5575);
PAINT SKYBLUE (4875 5575);
FORCEPROP 1 LAST TOLERANCE 10%
J 0
(4875 5625);
DISPLAY 0.617021 (4875 5625);
PAINT SKYBLUE (4875 5625);
FORCEPROP 1 LAST VALUE 1UF
J 0
(4875 5725);
DISPLAY 0.617021 (4875 5725);
PAINT SKYBLUE (4875 5725);
FORCEPROP 1 LAST VOLTAGE 16V
J 0
(4875 5675);
DISPLAY 0.617021 (4875 5675);
PAINT SKYBLUE (4875 5675);
FORCEPROP 1 LAST PACK_TYPE C0402
J 0
(4875 5525);
DISPLAY 0.617021 (4875 5525);
PAINT SKYBLUE (4875 5525);
FORCEPROP 1 LAST LOCATION PC255_P0_5
J 0
(4875 5775);
DISPLAY 0.617021 (4875 5775);
PAINT AQUA (4875 5775);
FORCEPROP 1 LASTPIN (4825 5725) $PN 1
J 0
(4835 5705);
DISPLAY 0.617021 (4835 5705);
PAINT MONO (4835 5705);
FORCEPROP 1 LASTPIN (4825 5525) $PN 2
J 0
(4835 5505);
DISPLAY 0.617021 (4835 5505);
PAINT MONO (4835 5505);
FORCEPROP 2 LAST CDS_LIB pure_quanta
J 0
(4825 5625);
DISPLAY INVISIBLE (4825 5625);
FORCEPROP 1 LAST PATH I52
J 0
(4875 5775);
DISPLAY 0.978723 (4875 5775);
PAINT WHITE (4875 5775);
DISPLAY INVISIBLE (4875 5775);
FORCEPROP 1 LAST LOCATION PC255_P0_5
J 0
(4875 5825);
DISPLAY 1.021277 (4875 5825);
PAINT AQUA (4875 5825);
DISPLAY INVISIBLE (4875 5825);
FORCEPROP 0 LAST $SEC 1
J 0
(4875 5825);
DISPLAY 0.680851 (4875 5825);
PAINT MONO (4875 5825);
DISPLAY INVISIBLE (4875 5825);
FORCEPROP 0 LAST CDS_SEC 1
J 0
(4875 5825);
DISPLAY 1.021277 (4875 5825);
DISPLAY INVISIBLE (4875 5825);
FORCEADD Q_CAP..1
(5225 5625);
FORCEPROP 1 LAST PART_NUMBER CH6223MEA01
J 0
(5275 5475);
DISPLAY 0.617021 (5275 5475);
PAINT BLUE (5275 5475);
DISPLAY INVISIBLE (5275 5475);
FORCEPROP 1 LAST MATERIAL X6S
J 0
(5275 5575);
DISPLAY 0.617021 (5275 5575);
PAINT SKYBLUE (5275 5575);
FORCEPROP 1 LAST TOLERANCE 20%
J 0
(5275 5625);
DISPLAY 0.617021 (5275 5625);
PAINT SKYBLUE (5275 5625);
FORCEPROP 1 LAST VALUE 22UF
J 0
(5275 5725);
DISPLAY 0.617021 (5275 5725);
PAINT SKYBLUE (5275 5725);
FORCEPROP 1 LAST VOLTAGE 16V
J 0
(5275 5675);
DISPLAY 0.617021 (5275 5675);
PAINT SKYBLUE (5275 5675);
FORCEPROP 1 LAST PACK_TYPE C0805
J 0
(5275 5525);
DISPLAY 0.617021 (5275 5525);
PAINT SKYBLUE (5275 5525);
FORCEPROP 1 LAST LOCATION PC259_P0_5
J 0
(5275 5775);
DISPLAY 0.617021 (5275 5775);
PAINT AQUA (5275 5775);
FORCEPROP 1 LASTPIN (5225 5725) $PN 1
J 0
(5235 5705);
DISPLAY 0.617021 (5235 5705);
PAINT MONO (5235 5705);
FORCEPROP 1 LASTPIN (5225 5525) $PN 2
J 0
(5235 5505);
DISPLAY 0.617021 (5235 5505);
PAINT MONO (5235 5505);
FORCEPROP 2 LAST CDS_LIB pure_quanta
J 0
(5225 5625);
DISPLAY INVISIBLE (5225 5625);
FORCEPROP 1 LAST PATH I53
J 0
(5275 5775);
DISPLAY 0.978723 (5275 5775);
PAINT WHITE (5275 5775);
DISPLAY INVISIBLE (5275 5775);
FORCEPROP 1 LAST LOCATION PC259_P0_5
J 0
(5275 5825);
DISPLAY 1.021277 (5275 5825);
PAINT AQUA (5275 5825);
DISPLAY INVISIBLE (5275 5825);
FORCEPROP 0 LAST $SEC 1
J 0
(5275 5825);
DISPLAY 0.680851 (5275 5825);
PAINT MONO (5275 5825);
DISPLAY INVISIBLE (5275 5825);
FORCEPROP 0 LAST CDS_SEC 1
J 0
(5275 5825);
DISPLAY 1.021277 (5275 5825);
DISPLAY INVISIBLE (5275 5825);
FORCEADD Q_CAP..1
(5625 5625);
FORCEPROP 1 LAST PART_NUMBER CH6223MEA01
J 0
(5675 5475);
DISPLAY 0.617021 (5675 5475);
PAINT BLUE (5675 5475);
DISPLAY INVISIBLE (5675 5475);
FORCEPROP 1 LAST MATERIAL X6S
J 0
(5675 5575);
DISPLAY 0.617021 (5675 5575);
PAINT SKYBLUE (5675 5575);
FORCEPROP 1 LAST TOLERANCE 20%
J 0
(5675 5625);
DISPLAY 0.617021 (5675 5625);
PAINT SKYBLUE (5675 5625);
FORCEPROP 1 LAST VALUE 22UF
J 0
(5675 5725);
DISPLAY 0.617021 (5675 5725);
PAINT SKYBLUE (5675 5725);
FORCEPROP 1 LAST VOLTAGE 16V
J 0
(5675 5675);
DISPLAY 0.617021 (5675 5675);
PAINT SKYBLUE (5675 5675);
FORCEPROP 1 LAST PACK_TYPE C0805
J 0
(5675 5525);
DISPLAY 0.617021 (5675 5525);
PAINT SKYBLUE (5675 5525);
FORCEPROP 1 LAST LOCATION PC261_P0_5
J 0
(5675 5775);
DISPLAY 0.617021 (5675 5775);
PAINT AQUA (5675 5775);
FORCEPROP 1 LASTPIN (5625 5725) $PN 1
J 0
(5635 5705);
DISPLAY 0.617021 (5635 5705);
PAINT MONO (5635 5705);
FORCEPROP 1 LASTPIN (5625 5525) $PN 2
J 0
(5635 5505);
DISPLAY 0.617021 (5635 5505);
PAINT MONO (5635 5505);
FORCEPROP 2 LAST CDS_LIB pure_quanta
J 0
(5625 5625);
DISPLAY INVISIBLE (5625 5625);
FORCEPROP 1 LAST PATH I54
J 0
(5675 5775);
DISPLAY 0.978723 (5675 5775);
PAINT WHITE (5675 5775);
DISPLAY INVISIBLE (5675 5775);
FORCEPROP 1 LAST LOCATION PC261_P0_5
J 0
(5675 5825);
DISPLAY 1.021277 (5675 5825);
PAINT AQUA (5675 5825);
DISPLAY INVISIBLE (5675 5825);
FORCEPROP 0 LAST $SEC 1
J 0
(5675 5825);
DISPLAY 0.680851 (5675 5825);
PAINT MONO (5675 5825);
DISPLAY INVISIBLE (5675 5825);
FORCEPROP 0 LAST CDS_SEC 1
J 0
(5675 5825);
DISPLAY 1.021277 (5675 5825);
DISPLAY INVISIBLE (5675 5825);
FORCEADD UNIVERSAL_GND..1
(6225 5200);
FORCEPROP 3 LASTPIN (6225 5250) SIG_NAME GND\g
J 0
(6235 5260);
DISPLAY 0.659574 (6235 5260);
PAINT MONO (6235 5260);
DISPLAY INVISIBLE (6235 5260);
FORCEPROP 2 LAST CDS_LIB logical_power
J 0
(6225 5200);
PAINT MONO (6225 5200);
DISPLAY INVISIBLE (6225 5200);
FORCEPROP 1 LAST HDL_POWER GND
J 1
(6250 5125);
DISPLAY 0.872340 (6250 5125);
PAINT GREEN (6250 5125);
DISPLAY INVISIBLE (6250 5125);
FORCEPROP 1 LAST PATH I55
J 0
(6300 5200);
DISPLAY 0.872340 (6300 5200);
PAINT AQUA (6300 5200);
DISPLAY INVISIBLE (6300 5200);
FORCEADD Q_CAP..1
(6000 5625);
FORCEPROP 1 LAST PART_NUMBER CH6223MEA01
J 0
(6050 5475);
DISPLAY 0.617021 (6050 5475);
PAINT BLUE (6050 5475);
DISPLAY INVISIBLE (6050 5475);
FORCEPROP 1 LAST PACK_TYPE C0805
J 0
(6050 5525);
DISPLAY 0.617021 (6050 5525);
PAINT SKYBLUE (6050 5525);
FORCEPROP 1 LAST VOLTAGE 16V
J 0
(6050 5675);
DISPLAY 0.617021 (6050 5675);
PAINT SKYBLUE (6050 5675);
FORCEPROP 1 LAST VALUE 22UF
J 0
(6050 5725);
DISPLAY 0.617021 (6050 5725);
PAINT SKYBLUE (6050 5725);
FORCEPROP 1 LAST TOLERANCE 20%
J 0
(6050 5625);
DISPLAY 0.617021 (6050 5625);
PAINT SKYBLUE (6050 5625);
FORCEPROP 1 LAST MATERIAL X6S
J 0
(6050 5575);
DISPLAY 0.617021 (6050 5575);
PAINT SKYBLUE (6050 5575);
FORCEPROP 1 LAST LOCATION PC263_P0_5
J 0
(6050 5775);
DISPLAY 0.617021 (6050 5775);
PAINT AQUA (6050 5775);
FORCEPROP 1 LASTPIN (6000 5725) $PN 1
J 0
(6010 5705);
DISPLAY 0.617021 (6010 5705);
PAINT MONO (6010 5705);
FORCEPROP 1 LASTPIN (6000 5525) $PN 2
J 0
(6010 5505);
DISPLAY 0.617021 (6010 5505);
PAINT MONO (6010 5505);
FORCEPROP 2 LAST CDS_LIB pure_quanta
J 0
(6000 5625);
DISPLAY INVISIBLE (6000 5625);
FORCEPROP 1 LAST PATH I56
J 0
(6050 5775);
DISPLAY 0.978723 (6050 5775);
PAINT WHITE (6050 5775);
DISPLAY INVISIBLE (6050 5775);
FORCEPROP 1 LAST LOCATION PC263_P0_5
J 0
(6050 5825);
DISPLAY 1.021277 (6050 5825);
PAINT AQUA (6050 5825);
DISPLAY INVISIBLE (6050 5825);
FORCEPROP 0 LAST $SEC 1
J 0
(6050 5825);
DISPLAY 0.680851 (6050 5825);
PAINT MONO (6050 5825);
DISPLAY INVISIBLE (6050 5825);
FORCEPROP 0 LAST CDS_SEC 1
J 0
(6050 5825);
DISPLAY 1.021277 (6050 5825);
DISPLAY INVISIBLE (6050 5825);
FORCEADD VCC15..1
(6225 6000);
FORCEPROP 3 LASTPIN (6225 5950) SIG_NAME SW_P12V_PVCCIN_CPU0_FLT\g
J 0
(6235 5960);
DISPLAY 0.659574 (6235 5960);
PAINT MONO (6235 5960);
DISPLAY INVISIBLE (6235 5960);
FORCEPROP 1 LAST HDL_POWER SW_P12V_PVCCIN_CPU0_FLT
J 1
(6275 6050);
DISPLAY 0.617021 (6275 6050);
PAINT GREEN (6275 6050);
FORCEPROP 2 LAST CDS_LIB logical_power
J 0
(6225 6000);
DISPLAY INVISIBLE (6225 6000);
FORCEPROP 1 LAST PATH I57
J 0
(6275 6025);
DISPLAY 0.872340 (6275 6025);
PAINT AQUA (6275 6025);
DISPLAY INVISIBLE (6275 6025);
FORCEADD OFFPAGE..3
(7050 4475);
FORCEPROP 2 LAST $XR0 270 
J 0
(7264 4475);
DISPLAY 0.638298 (7264 4475);
PAINT MONO (7264 4475);
FORCEPROP 1 LAST COMMENT_BODY TRUE
J 0
(7000 4375);
DISPLAY 0.872340 (7000 4375);
PAINT GREEN (7000 4375);
DISPLAY INVISIBLE (7000 4375);
FORCEPROP 1 LAST OFFPAGE TRUE
J 0
(7375 4350);
DISPLAY 0.872340 (7375 4350);
PAINT GREEN (7375 4350);
DISPLAY INVISIBLE (7375 4350);
FORCEPROP 2 LAST CDS_LIB standard
J 0
(7050 4475);
DISPLAY INVISIBLE (7050 4475);
FORCEPROP 2 LAST PATH I58
J 0
(7275 4525);
DISPLAY 1.021277 (7275 4525);
DISPLAY INVISIBLE (7275 4525);
FORCEADD Q_CAP..1
(8150 1700);
FORCEPROP 1 LAST PART_NUMBER CH622KMEA03
J 0
(8200 1525);
DISPLAY 0.617021 (8200 1525);
PAINT BLUE (8200 1525);
DISPLAY INVISIBLE (8200 1525);
FORCEPROP 1 LAST PACK_TYPE C0805
J 0
(8200 1575);
DISPLAY 0.617021 (8200 1575);
PAINT SKYBLUE (8200 1575);
FORCEPROP 1 LAST VOLTAGE 4V
J 0
(8200 1725);
DISPLAY 0.617021 (8200 1725);
PAINT SKYBLUE (8200 1725);
FORCEPROP 1 LAST VALUE 22UF
J 0
(8200 1775);
DISPLAY 0.617021 (8200 1775);
PAINT SKYBLUE (8200 1775);
FORCEPROP 1 LAST TOLERANCE 20%
J 0
(8200 1675);
DISPLAY 0.617021 (8200 1675);
PAINT SKYBLUE (8200 1675);
FORCEPROP 1 LAST MATERIAL X6S
J 0
(8200 1625);
DISPLAY 0.617021 (8200 1625);
PAINT SKYBLUE (8200 1625);
FORCEPROP 1 LAST LOCATION PC268_P0_6
J 0
(8200 1825);
DISPLAY 0.617021 (8200 1825);
PAINT AQUA (8200 1825);
FORCEPROP 1 LASTPIN (8150 1800) $PN 1
J 0
(8160 1780);
DISPLAY 0.617021 (8160 1780);
PAINT MONO (8160 1780);
FORCEPROP 1 LASTPIN (8150 1600) $PN 2
J 0
(8160 1580);
DISPLAY 0.617021 (8160 1580);
PAINT MONO (8160 1580);
FORCEPROP 2 LAST CDS_LIB pure_quanta
J 0
(8150 1700);
DISPLAY INVISIBLE (8150 1700);
FORCEPROP 1 LAST PATH I59
J 0
(8200 1850);
DISPLAY 0.978723 (8200 1850);
PAINT WHITE (8200 1850);
DISPLAY INVISIBLE (8200 1850);
FORCEPROP 1 LAST LOCATION PC268_P0_6
J 0
(8200 1875);
DISPLAY 1.021277 (8200 1875);
PAINT AQUA (8200 1875);
DISPLAY INVISIBLE (8200 1875);
FORCEPROP 0 LAST $SEC 1
J 0
(8200 1875);
DISPLAY 0.680851 (8200 1875);
PAINT MONO (8200 1875);
DISPLAY INVISIBLE (8200 1875);
FORCEPROP 0 LAST CDS_SEC 1
J 0
(8200 1875);
DISPLAY 1.021277 (8200 1875);
DISPLAY INVISIBLE (8200 1875);
FORCEADD OFFPAGE..5
(2150 1400);
FORCEPROP 2 LAST $XR4 266 
J 0
(1895 1472);
DISPLAY 0.638298 (1895 1472);
PAINT MONO (1895 1472);
FORCEPROP 2 LAST $XR3 270 
J 0
(1895 1328);
DISPLAY 0.638298 (1895 1328);
PAINT MONO (1895 1328);
FORCEPROP 2 LAST $XR2 269 
J 0
(1895 1436);
DISPLAY 0.638298 (1895 1436);
PAINT MONO (1895 1436);
FORCEPROP 2 LAST $XR1 268 
J 0
(1895 1364);
DISPLAY 0.638298 (1895 1364);
PAINT MONO (1895 1364);
FORCEPROP 2 LAST $XR0 267 
J 0
(1895 1400);
DISPLAY 0.638298 (1895 1400);
PAINT MONO (1895 1400);
FORCEPROP 1 LAST COMMENT_BODY TRUE
J 0
(2250 1325);
DISPLAY 0.872340 (2250 1325);
PAINT GREEN (2250 1325);
DISPLAY INVISIBLE (2250 1325);
FORCEPROP 1 LAST OFFPAGE TRUE
J 0
(2475 1275);
DISPLAY 0.872340 (2475 1275);
PAINT GREEN (2475 1275);
DISPLAY INVISIBLE (2475 1275);
FORCEPROP 2 LAST CDS_LIB standard
J 0
(2150 1400);
DISPLAY INVISIBLE (2150 1400);
FORCEPROP 2 LAST PATH I6
J 0
(1900 1525);
DISPLAY 1.021277 (1900 1525);
DISPLAY INVISIBLE (1900 1525);
FORCEADD UNIVERSAL_GND..1
(8450 1325);
FORCEPROP 3 LASTPIN (8450 1375) SIG_NAME GND\g
J 0
(8460 1385);
DISPLAY 0.659574 (8460 1385);
PAINT MONO (8460 1385);
DISPLAY INVISIBLE (8460 1385);
FORCEPROP 2 LAST CDS_LIB logical_power
J 0
(8450 1325);
PAINT MONO (8450 1325);
DISPLAY INVISIBLE (8450 1325);
FORCEPROP 1 LAST HDL_POWER GND
J 1
(8475 1250);
DISPLAY 0.872340 (8475 1250);
PAINT GREEN (8475 1250);
DISPLAY INVISIBLE (8475 1250);
FORCEPROP 1 LAST PATH I60
J 0
(8525 1325);
DISPLAY 0.872340 (8525 1325);
PAINT AQUA (8525 1325);
DISPLAY INVISIBLE (8525 1325);
FORCEADD VCC15..1
(8450 2100);
FORCEPROP 3 LASTPIN (8450 2050) SIG_NAME PVCCIN_CPU0\g
J 0
(8460 2060);
DISPLAY 0.659574 (8460 2060);
PAINT MONO (8460 2060);
DISPLAY INVISIBLE (8460 2060);
FORCEPROP 1 LAST HDL_POWER PVCCIN_CPU0
J 1
(8450 2150);
DISPLAY 0.617021 (8450 2150);
PAINT GREEN (8450 2150);
FORCEPROP 2 LAST CDS_LIB logical_power
J 0
(8450 2100);
DISPLAY INVISIBLE (8450 2100);
FORCEPROP 1 LAST PATH I61
J 0
(8500 2125);
DISPLAY 0.872340 (8500 2125);
PAINT AQUA (8500 2125);
DISPLAY INVISIBLE (8500 2125);
FORCEADD UNIVERSAL_GND..1
(8650 4150);
FORCEPROP 3 LASTPIN (8650 4200) SIG_NAME GND\g
J 0
(8660 4210);
DISPLAY 0.659574 (8660 4210);
PAINT MONO (8660 4210);
DISPLAY INVISIBLE (8660 4210);
FORCEPROP 2 LAST CDS_LIB logical_power
J 0
(8650 4150);
PAINT MONO (8650 4150);
DISPLAY INVISIBLE (8650 4150);
FORCEPROP 1 LAST HDL_POWER GND
J 1
(8675 4075);
DISPLAY 0.872340 (8675 4075);
PAINT GREEN (8675 4075);
DISPLAY INVISIBLE (8675 4075);
FORCEPROP 1 LAST PATH I62
J 0
(8725 4150);
DISPLAY 0.872340 (8725 4150);
PAINT AQUA (8725 4150);
DISPLAY INVISIBLE (8725 4150);
FORCEADD Q_CAP..1
(7925 4525);
FORCEPROP 1 LAST PART_NUMBER CH622KMEA03
J 0
(7975 4350);
DISPLAY 0.617021 (7975 4350);
PAINT BLUE (7975 4350);
DISPLAY INVISIBLE (7975 4350);
FORCEPROP 1 LAST PACK_TYPE C0805
J 0
(7975 4400);
DISPLAY 0.617021 (7975 4400);
PAINT SKYBLUE (7975 4400);
FORCEPROP 1 LAST VOLTAGE 4V
J 0
(7975 4550);
DISPLAY 0.617021 (7975 4550);
PAINT SKYBLUE (7975 4550);
FORCEPROP 1 LAST VALUE 22UF
J 0
(7975 4600);
DISPLAY 0.617021 (7975 4600);
PAINT SKYBLUE (7975 4600);
FORCEPROP 1 LAST TOLERANCE 20%
J 0
(7975 4500);
DISPLAY 0.617021 (7975 4500);
PAINT SKYBLUE (7975 4500);
FORCEPROP 1 LAST MATERIAL X6S
J 0
(7975 4450);
DISPLAY 0.617021 (7975 4450);
PAINT SKYBLUE (7975 4450);
FORCEPROP 1 LAST LOCATION PC267_P0_5
J 0
(7975 4650);
DISPLAY 0.617021 (7975 4650);
PAINT AQUA (7975 4650);
FORCEPROP 1 LASTPIN (7925 4625) $PN 1
J 0
(7935 4605);
DISPLAY 0.617021 (7935 4605);
PAINT MONO (7935 4605);
FORCEPROP 1 LASTPIN (7925 4425) $PN 2
J 0
(7935 4405);
DISPLAY 0.617021 (7935 4405);
PAINT MONO (7935 4405);
FORCEPROP 2 LAST CDS_LIB pure_quanta
J 0
(7925 4525);
DISPLAY INVISIBLE (7925 4525);
FORCEPROP 1 LAST PATH I63
J 0
(7975 4675);
DISPLAY 0.978723 (7975 4675);
PAINT WHITE (7975 4675);
DISPLAY INVISIBLE (7975 4675);
FORCEPROP 1 LAST LOCATION PC267_P0_5
J 0
(7975 4700);
DISPLAY 1.021277 (7975 4700);
PAINT AQUA (7975 4700);
DISPLAY INVISIBLE (7975 4700);
FORCEPROP 0 LAST $SEC 1
J 0
(7975 4700);
DISPLAY 0.680851 (7975 4700);
PAINT MONO (7975 4700);
DISPLAY INVISIBLE (7975 4700);
FORCEPROP 0 LAST CDS_SEC 1
J 0
(7975 4700);
DISPLAY 1.021277 (7975 4700);
DISPLAY INVISIBLE (7975 4700);
FORCEADD Q_CAP..1
(8350 4525);
FORCEPROP 1 LAST PART_NUMBER CH622KMEA03
J 0
(8400 4350);
DISPLAY 0.617021 (8400 4350);
PAINT BLUE (8400 4350);
DISPLAY INVISIBLE (8400 4350);
FORCEPROP 1 LAST PACK_TYPE C0805
J 0
(8400 4400);
DISPLAY 0.617021 (8400 4400);
PAINT SKYBLUE (8400 4400);
FORCEPROP 1 LAST VOLTAGE 4V
J 0
(8400 4550);
DISPLAY 0.617021 (8400 4550);
PAINT SKYBLUE (8400 4550);
FORCEPROP 1 LAST VALUE 22UF
J 0
(8400 4600);
DISPLAY 0.617021 (8400 4600);
PAINT SKYBLUE (8400 4600);
FORCEPROP 1 LAST TOLERANCE 20%
J 0
(8400 4500);
DISPLAY 0.617021 (8400 4500);
PAINT SKYBLUE (8400 4500);
FORCEPROP 1 LAST MATERIAL X6S
J 0
(8400 4450);
DISPLAY 0.617021 (8400 4450);
PAINT SKYBLUE (8400 4450);
FORCEPROP 1 LAST LOCATION PC269_P0_5
J 0
(8400 4650);
DISPLAY 0.617021 (8400 4650);
PAINT AQUA (8400 4650);
FORCEPROP 1 LASTPIN (8350 4625) $PN 1
J 0
(8360 4605);
DISPLAY 0.617021 (8360 4605);
PAINT MONO (8360 4605);
FORCEPROP 1 LASTPIN (8350 4425) $PN 2
J 0
(8360 4405);
DISPLAY 0.617021 (8360 4405);
PAINT MONO (8360 4405);
FORCEPROP 2 LAST CDS_LIB pure_quanta
J 0
(8350 4525);
DISPLAY INVISIBLE (8350 4525);
FORCEPROP 1 LAST PATH I64
J 0
(8400 4675);
DISPLAY 0.978723 (8400 4675);
PAINT WHITE (8400 4675);
DISPLAY INVISIBLE (8400 4675);
FORCEPROP 1 LAST LOCATION PC269_P0_5
J 0
(8400 4700);
DISPLAY 1.021277 (8400 4700);
PAINT AQUA (8400 4700);
DISPLAY INVISIBLE (8400 4700);
FORCEPROP 0 LAST $SEC 1
J 0
(8400 4700);
DISPLAY 0.680851 (8400 4700);
PAINT MONO (8400 4700);
DISPLAY INVISIBLE (8400 4700);
FORCEPROP 0 LAST CDS_SEC 1
J 0
(8400 4700);
DISPLAY 1.021277 (8400 4700);
DISPLAY INVISIBLE (8400 4700);
FORCEADD VCC15..1
(8650 4925);
FORCEPROP 3 LASTPIN (8650 4875) SIG_NAME PVCCIN_CPU0\g
J 0
(8660 4885);
DISPLAY 0.659574 (8660 4885);
PAINT MONO (8660 4885);
DISPLAY INVISIBLE (8660 4885);
FORCEPROP 1 LAST HDL_POWER PVCCIN_CPU0
J 1
(8650 4975);
DISPLAY 0.617021 (8650 4975);
PAINT GREEN (8650 4975);
FORCEPROP 2 LAST CDS_LIB logical_power
J 0
(8650 4925);
DISPLAY INVISIBLE (8650 4925);
FORCEPROP 1 LAST PATH I65
J 0
(8700 4950);
DISPLAY 0.872340 (8700 4950);
PAINT AQUA (8700 4950);
DISPLAY INVISIBLE (8700 4950);
FORCEADD ISL99390FRZTR5935..1
(3625 4725);
FORCEPROP 1 LAST PART_NUMBER AL099390004
J 0
(3325 5525);
DISPLAY 0.617021 (3325 5525);
PAINT BLUE (3325 5525);
DISPLAY INVISIBLE (3325 5525);
FORCEPROP 2 LAST PART_TYPE SMLF
J 0
(3325 5750);
DISPLAY 0.638298 (3325 5750);
FORCEPROP 1 LAST MATERIAL IC
J 0
(3325 5450);
DISPLAY 0.617021 (3325 5450);
PAINT SKYBLUE (3325 5450);
FORCEPROP 2 LAST VALUE ISL99390FRZ-TR5935
J 0
(3325 5700);
DISPLAY 0.617021 (3325 5700);
PAINT SKYBLUE (3325 5700);
FORCEPROP 1 LAST LOCATION PU9_P0_5
J 0
(3325 5600);
DISPLAY 0.617021 (3325 5600);
PAINT AQUA (3325 5600);
FORCEPROP 2 LASTPIN (4025 4275) $PN 2
J 0
(4035 4285);
DISPLAY 0.617021 (4035 4285);
PAINT MONO (4035 4285);
FORCEPROP 2 LASTPIN (4025 5075) $PN 33
J 0
(4035 5085);
DISPLAY 0.617021 (4035 5085);
PAINT MONO (4035 5085);
FORCEPROP 2 LASTPIN (3175 4475) $PN 31
J 2
(3165 4485);
DISPLAY 0.617021 (3165 4485);
PAINT MONO (3165 4485);
FORCEPROP 2 LASTPIN (3175 4875) $PN 35
J 2
(3165 4885);
DISPLAY 0.617021 (3165 4885);
PAINT MONO (3165 4885);
FORCEPROP 2 LASTPIN (4025 4425) $PN 6
J 0
(4035 4435);
DISPLAY 0.617021 (4035 4435);
PAINT MONO (4035 4435);
FORCEPROP 2 LASTPIN (4025 4375) $PN 41
J 0
(4035 4385);
DISPLAY 0.617021 (4035 4385);
PAINT MONO (4035 4385);
FORCEPROP 2 LASTPIN (3175 4725) $PN 38
J 2
(3165 4735);
DISPLAY 0.617021 (3165 4735);
PAINT MONO (3165 4735);
FORCEPROP 2 LASTPIN (3175 4425) $PN 37
J 2
(3165 4435);
DISPLAY 0.617021 (3165 4435);
PAINT MONO (3165 4435);
FORCEPROP 2 LASTPIN (4025 4225) $PN 5
J 0
(4035 4235);
DISPLAY 0.617021 (4035 4235);
PAINT MONO (4035 4235);
FORCEPROP 2 LASTPIN (4025 4175) $PN 7_9-20_24
J 0
(4035 4185);
DISPLAY 0.617021 (4035 4185);
PAINT MONO (4035 4185);
FORCEPROP 2 LASTPIN (4025 4125) $PN 40
J 0
(4035 4135);
DISPLAY 0.617021 (4035 4135);
PAINT MONO (4035 4135);
FORCEPROP 2 LASTPIN (4025 4825) $PN 32
J 0
(4035 4835);
DISPLAY 0.617021 (4035 4835);
PAINT MONO (4035 4835);
FORCEPROP 2 LASTPIN (3175 5375) $PN 4
J 2
(3165 5385);
DISPLAY 0.617021 (3165 5385);
PAINT MONO (3165 5385);
FORCEPROP 2 LASTPIN (3175 4125) $PN 34
J 2
(3165 4135);
DISPLAY 0.617021 (3165 4135);
PAINT MONO (3165 4135);
FORCEPROP 2 LASTPIN (3175 4625) $PN 39
J 2
(3165 4635);
DISPLAY 0.617021 (3165 4635);
PAINT MONO (3165 4635);
FORCEPROP 2 LASTPIN (4025 4725) $PN 10_19
J 0
(4035 4735);
DISPLAY 0.617021 (4035 4735);
PAINT MONO (4035 4735);
FORCEPROP 2 LASTPIN (3175 4225) $PN 36
J 2
(3165 4235);
DISPLAY 0.617021 (3165 4235);
PAINT MONO (3165 4235);
FORCEPROP 2 LASTPIN (3175 5075) $PN 3
J 2
(3165 5085);
DISPLAY 0.617021 (3165 5085);
PAINT MONO (3165 5085);
FORCEPROP 2 LASTPIN (4025 5375) $PN 25_29
J 0
(4035 5385);
DISPLAY 0.617021 (4035 5385);
PAINT MONO (4035 5385);
FORCEPROP 2 LASTPIN (4025 5325) $PN 30
J 0
(4035 5335);
DISPLAY 0.617021 (4035 5335);
PAINT MONO (4035 5335);
FORCEPROP 2 LASTPIN (4025 4475) $PN 1
J 0
(4035 4485);
DISPLAY 0.617021 (4035 4485);
PAINT MONO (4035 4485);
FORCEPROP 1 LAST NEEDS_NO_SIZE TRUE
J 0
(3625 4725);
DISPLAY 0.723404 (3625 4725);
PAINT GREEN (3625 4725);
DISPLAY INVISIBLE (3625 4725);
FORCEPROP 1 LAST CDS_LMAN_SYM_OUTLINE -300,700,250,-650
J 0
(3625 4725);
DISPLAY 0.468085 (3625 4725);
PAINT GREEN (3625 4725);
DISPLAY INVISIBLE (3625 4725);
FORCEPROP 2 LAST CDS_LIB pure_quanta
J 0
(3625 4725);
DISPLAY INVISIBLE (3625 4725);
FORCEPROP 1 LAST PATH I66
J 0
(3625 4725);
DISPLAY 0.723404 (3625 4725);
PAINT GREEN (3625 4725);
DISPLAY INVISIBLE (3625 4725);
FORCEPROP 2 LAST $SEC 1
J 0
(3325 5775);
DISPLAY 0.680851 (3325 5775);
PAINT MONO (3325 5775);
DISPLAY INVISIBLE (3325 5775);
FORCEPROP 2 LAST CDS_SEC 1
J 0
(3325 5775);
DISPLAY 1.021277 (3325 5775);
DISPLAY INVISIBLE (3325 5775);
FORCEADD OFFPAGE..1
(2150 1300);
FORCEPROP 2 LAST $XR0 266 
J 0
(1724 1300);
DISPLAY 0.638298 (1724 1300);
PAINT MONO (1724 1300);
FORCEPROP 1 LAST COMMENT_BODY TRUE
J 0
(2275 1200);
DISPLAY 0.872340 (2275 1200);
PAINT GREEN (2275 1200);
DISPLAY INVISIBLE (2275 1200);
FORCEPROP 1 LAST OFFPAGE TRUE
J 0
(2475 1175);
DISPLAY 0.872340 (2475 1175);
PAINT GREEN (2475 1175);
DISPLAY INVISIBLE (2475 1175);
FORCEPROP 2 LAST CDS_LIB standard
J 0
(2150 1300);
DISPLAY INVISIBLE (2150 1300);
FORCEPROP 2 LAST PATH I7
J 0
(1725 1350);
DISPLAY 1.021277 (1725 1350);
DISPLAY INVISIBLE (1725 1350);
FORCEADD OFFPAGE..5
(2150 1900);
FORCEPROP 2 LAST $XR0 266 
J 0
(1895 1900);
DISPLAY 0.638298 (1895 1900);
PAINT MONO (1895 1900);
FORCEPROP 1 LAST COMMENT_BODY TRUE
J 0
(2250 1825);
DISPLAY 0.872340 (2250 1825);
PAINT GREEN (2250 1825);
DISPLAY INVISIBLE (2250 1825);
FORCEPROP 1 LAST OFFPAGE TRUE
J 0
(2475 1775);
DISPLAY 0.872340 (2475 1775);
PAINT GREEN (2475 1775);
DISPLAY INVISIBLE (2475 1775);
FORCEPROP 2 LAST CDS_LIB standard
J 0
(2150 1900);
DISPLAY INVISIBLE (2150 1900);
FORCEPROP 2 LAST PATH I8
J 0
(1900 1950);
DISPLAY 1.021277 (1900 1950);
DISPLAY INVISIBLE (1900 1950);
FORCEADD OFFPAGE..1
(2150 1800);
FORCEPROP 2 LAST $XR6 272 
J 0
(1148 1800);
DISPLAY 0.638298 (1148 1800);
PAINT MONO (1148 1800);
FORCEPROP 2 LAST $XR5 271 
J 0
(1268 1800);
DISPLAY 0.638298 (1268 1800);
PAINT MONO (1268 1800);
FORCEPROP 2 LAST $XR4 270 
J 0
(1388 1800);
DISPLAY 0.638298 (1388 1800);
PAINT MONO (1388 1800);
FORCEPROP 2 LAST $XR3 269 
J 0
(1508 1800);
DISPLAY 0.638298 (1508 1800);
PAINT MONO (1508 1800);
FORCEPROP 2 LAST $XR2 268 
J 0
(1628 1800);
DISPLAY 0.638298 (1628 1800);
PAINT MONO (1628 1800);
FORCEPROP 2 LAST $XR1 267 
J 0
(1748 1800);
DISPLAY 0.638298 (1748 1800);
PAINT MONO (1748 1800);
FORCEPROP 2 LAST $XR0 266 
J 0
(1868 1800);
DISPLAY 0.638298 (1868 1800);
PAINT MONO (1868 1800);
FORCEPROP 1 LAST COMMENT_BODY TRUE
J 0
(2275 1700);
DISPLAY 0.872340 (2275 1700);
PAINT GREEN (2275 1700);
DISPLAY INVISIBLE (2275 1700);
FORCEPROP 1 LAST OFFPAGE TRUE
J 0
(2475 1675);
DISPLAY 0.872340 (2475 1675);
PAINT GREEN (2475 1675);
DISPLAY INVISIBLE (2475 1675);
FORCEPROP 2 LAST CDS_LIB standard
J 0
(2150 1800);
DISPLAY INVISIBLE (2150 1800);
FORCEPROP 2 LAST PATH I9
J 0
(1875 1850);
DISPLAY 1.021277 (1875 1850);
DISPLAY INVISIBLE (1875 1850);
FORCEADD DNS..1
(1675 1375);
PAINT RED (1675 1375);
FORCEPROP 2 LAST CDS_LIB mstr_misc
J 0
(1675 1375);
PAINT MONO (1675 1375);
DISPLAY INVISIBLE (1675 1375);
FORCEPROP 1 LAST COMMENT_BODY TRUE
R 1
J 0
(1750 1150);
DISPLAY 0.872340 (1750 1150);
PAINT GREEN (1750 1150);
DISPLAY INVISIBLE (1750 1150);
FORCEADD DNS..1
(1700 4200);
PAINT RED (1700 4200);
FORCEPROP 2 LAST CDS_LIB mstr_misc
J 0
(1700 4200);
PAINT MONO (1700 4200);
DISPLAY INVISIBLE (1700 4200);
FORCEPROP 1 LAST COMMENT_BODY TRUE
R 1
J 0
(1775 3975);
DISPLAY 0.872340 (1775 3975);
PAINT GREEN (1775 3975);
DISPLAY INVISIBLE (1775 3975);
FORCEADD QUANTA_TITLE_BLOCK_C..1
(9050 325);
FORCEPROP 0 LAST CDS_CON_LAST_MODIFIED Fri Aug 25 14:04:39 2023
J 0
(7165 340);
DISPLAY INVISIBLE (7165 340);
FORCEPROP 1 LAST CUSTOM_TXT_CDS <CON_LAST_MODIFIED>
J 0
(7165 340);
DISPLAY 0.978723 (7165 340);
FORCEPROP 2 LAST CUSTOM_TXT_CDS <XR_PAGE_TITLE>
J 0
(1160 5575);
DISPLAY 0.638298 (1160 5575);
PAINT PINK (1160 5575);
DISPLAY INVISIBLE (1160 5575);
FORCEPROP 1 LAST CUSTOM_TXT_CDS <NAME_2>
J 0
(5875 375);
FORCEPROP 1 LAST CUSTOM_TXT_CDS <NAME_1>
J 0
(5875 500);
FORCEPROP 1 LAST CUSTOM_TXT_CDS <Q_NUMBER>
J 0
(7647 428);
DISPLAY 1.212766 (7647 428);
FORCEPROP 1 LAST CUSTOM_TXT_CDS <Q_PROJ>
J 0
(6668 427);
DISPLAY 1.212766 (6668 427);
FORCEPROP 1 LAST CUSTOM_TXT_CDS <Q_REV>
J 0
(8866 428);
DISPLAY 1.212766 (8866 428);
FORCEPROP 1 LAST CUSTOM_TXT_CDS <CON_PAGE_NUM> OF <CON_TOTAL_PAGES>
J 0
(8604 343);
DISPLAY 0.978723 (8604 343);
FORCEPROP 1 LAST Q_TITLE VCCIN CPU0 VR PHASE 5&6 (4/7)
J 0
(-250 400);
DISPLAY 2.446809 (-250 400);
PAINT GREEN (-250 400);
FORCEPROP 1 LAST Q_DEPT 
J 1
(5287 374);
DISPLAY 1.957447 (5287 374);
PAINT GREEN (5287 374);
FORCEPROP 2 LAST CDS_XR_PAGE_TITLE CR-269 : @S9S_MB_2U_LIB.S9S_MB_2U(SCH_1):PAGE269
J 0
(1160 5575);
DISPLAY 0.638298 (1160 5575);
PAINT PINK (1160 5575);
DISPLAY INVISIBLE (1160 5575);
FORCEPROP 1 LAST COMMENT_BODY TRUE
J 0
(9062 312);
DISPLAY 0.978723 (9062 312);
PAINT GREEN (9062 312);
DISPLAY INVISIBLE (9062 312);
FORCEPROP 2 LAST CDS_LIB pure_quanta
J 0
(9050 325);
DISPLAY INVISIBLE (9050 325);
FORCEPROP 1 LAST CDS_LMAN_SYM_OUTLINE -9475,6775,100,-125
J 0
(9050 325);
DISPLAY 0.468085 (9050 325);
PAINT GREEN (9050 325);
DISPLAY INVISIBLE (9050 325);
FORCEPROP 2 LAST PAGE_BORDER TRUE
J 0
(1160 5575);
DISPLAY 0.638298 (1160 5575);
PAINT PINK (1160 5575);
DISPLAY INVISIBLE (1160 5575);
WIRE 16 -1 (2075 3125)(2075 3175);
WIRE 16 -1 (2500 3125)(2075 3125);
WIRE 16 -1 (2075 3000)(2075 3125);
WIRE 16 -1 (2100 5950)(2100 6000);
WIRE 16 -1 (2525 5950)(2100 5950);
WIRE 16 -1 (2100 5825)(2100 5950);
WIRE 16 -1 (6200 3125)(6200 3050);
WIRE 16 -1 (6225 5950)(6225 5875);
WIRE 16 -1 (8450 2050)(8450 1900);
WIRE 16 -1 (8650 4875)(8650 4725);
WIRE 16 -1 (1675 1300)(1675 1225);
WIRE 16 -1 (1575 1700)(1575 1675);
WIRE 16 -1 (1575 1700)(2300 1700);
WIRE 16 -1 (1700 4125)(1700 4050);
WIRE 16 -1 (2075 2300)(2075 2200);
WIRE 16 -1 (2500 2800)(2500 2725);
WIRE 16 -1 (1600 4525)(1600 4500);
WIRE 16 -1 (1600 4525)(2325 4525);
WIRE 16 -1 (2100 5125)(2100 5025);
WIRE 16 -1 (2525 5625)(2525 5550);
WIRE 16 -1 (4250 1300)(4250 1225);
WIRE 16 -1 (4250 1350)(4250 1300);
WIRE 16 -1 (4000 1300)(4250 1300);
WIRE 16 -1 (4275 4125)(4275 4050);
WIRE 16 -1 (4275 4175)(4275 4125);
WIRE 16 -1 (4025 4125)(4275 4125);
WIRE 16 -1 (6200 2425)(6200 2550);
WIRE 16 -1 (6225 5250)(6225 5375);
WIRE 16 -1 (8450 1375)(8450 1475);
WIRE 16 -1 (8650 4200)(8650 4300);
WIRE 16 -1 (7625 4175)(6250 4175);
WIRE 16 -1 (7625 4725)(6475 4725);
WIRE 16 -1 (7625 4725)(7625 4175);
WIRE 16 -1 (8350 4625)(8350 4725);
WIRE 16 -1 (8650 4725)(8350 4725);
WIRE 16 -1 (7925 4725)(7625 4725);
WIRE 16 -1 (7925 4725)(7925 4625);
WIRE 16 -1 (7925 4725)(8350 4725);
WIRE 16 -1 (7925 4300)(7925 4425);
WIRE 16 -1 (8350 4300)(7925 4300);
WIRE 16 -1 (8350 4425)(8350 4300);
WIRE 16 -1 (8650 4300)(8350 4300);
WIRE 16 -1 (7725 1475)(7725 1600);
WIRE 16 -1 (8150 1475)(7725 1475);
WIRE 16 -1 (8150 1475)(8150 1600);
WIRE 16 -1 (8450 1475)(8150 1475);
WIRE 16 -1 (7625 1375)(6225 1375);
WIRE 16 -1 (7625 1900)(6425 1900);
WIRE 16 -1 (7625 1900)(7625 1375);
WIRE 16 -1 (8150 1900)(8150 1800);
WIRE 16 -1 (8150 1900)(8450 1900);
WIRE 16 -1 (7725 1900)(7625 1900);
WIRE 16 -1 (7725 1900)(7725 1800);
WIRE 16 -1 (7725 1900)(8150 1900);
WIRE 16 -1 (6475 4475)(7000 4475);
FORCEPROP 2 LAST SIG_NAME IND_P0_CPL8
J 0
(6565 4485);
DISPLAY 0.617021 (6565 4485);
WIRE 16 -1 (4025 5325)(4200 5325);
WIRE 16 -1 (4025 5375)(4200 5375);
WIRE 16 -1 (4200 5325)(4200 5375);
WIRE 16 -1 (4200 5875)(4200 5375);
WIRE 16 -1 (4200 5875)(4425 5875);
WIRE 16 -1 (4425 5725)(4425 5875);
WIRE 16 -1 (4425 5875)(4825 5875);
WIRE 16 -1 (4825 5725)(4825 5875);
WIRE 16 -1 (4825 5875)(5225 5875);
WIRE 16 -1 (5225 5875)(5225 5725);
WIRE 16 -1 (5225 5875)(5625 5875);
WIRE 16 -1 (5625 5725)(5625 5875);
WIRE 16 -1 (5625 5875)(6000 5875);
WIRE 16 -1 (6000 5725)(6000 5875);
WIRE 16 -1 (6225 5875)(6000 5875);
WIRE 16 -1 (4425 5525)(4425 5375);
WIRE 16 -1 (4425 5375)(4825 5375);
WIRE 16 -1 (4825 5525)(4825 5375);
WIRE 16 -1 (5225 5375)(4825 5375);
WIRE 16 -1 (5225 5525)(5225 5375);
WIRE 16 -1 (5225 5375)(5625 5375);
WIRE 16 -1 (5625 5525)(5625 5375);
WIRE 16 -1 (5625 5375)(6000 5375);
WIRE 16 -1 (6000 5525)(6000 5375);
WIRE 16 -1 (6225 5375)(6000 5375);
WIRE 16 -1 (4875 4475)(5675 4475);
FORCEPROP 2 LAST SIG_NAME IND_P0_CPL5
J 0
(5040 4485);
DISPLAY 0.617021 (5040 4485);
WIRE 16 -1 (4975 5175)(5600 5175);
FORCEPROP 2 LAST SIG_NAME SW_PVCCIN_CPU0_BOOT5_R
J 0
(5290 5185);
DISPLAY 0.617021 (5290 5185);
WIRE 16 -1 (5600 5175)(5600 5100);
WIRE 16 -1 (4025 4725)(5675 4725);
FORCEPROP 2 LAST SIG_NAME SW_PVCCIN_CPU0_SW5
J 0
(4215 4735);
DISPLAY 0.617021 (4215 4735);
WIRE 16 -1 (4025 4825)(5600 4825);
FORCEPROP 2 LAST SIG_NAME SW_PVCCIN_CPU0_BOOTR5
J 0
(4215 4835);
DISPLAY 0.617021 (4215 4835);
WIRE 16 -1 (5600 4825)(5600 4900);
WIRE 16 -1 (4025 5075)(4175 5075);
WIRE 16 -1 (4175 5075)(4175 5175);
FORCEPROP 2 LAST SIG_NAME SW_PVCCIN_CPU0_BOOT5
J 0
(3990 5185);
DISPLAY 0.617021 (3990 5185);
WIRE 16 -1 (4175 5175)(4775 5175);
WIRE 16 -1 (6050 4175)(4400 4175);
FORCEPROP 2 LAST SIG_NAME PVCCIN_CPU0_VOS5
J 0
(4590 4185);
DISPLAY 0.617021 (4590 4185);
WIRE 16 -1 (4400 4475)(4400 4175);
WIRE 16 -1 (4025 4475)(4400 4475);
WIRE 16 -1 (4000 2500)(4175 2500);
WIRE 16 -1 (4000 2550)(4175 2550);
WIRE 16 -1 (4175 2500)(4175 2550);
WIRE 16 -1 (4175 3050)(4175 2550);
WIRE 16 -1 (4175 3050)(4400 3050);
WIRE 16 -1 (4400 2900)(4400 3050);
WIRE 16 -1 (4400 3050)(4800 3050);
WIRE 16 -1 (4800 2900)(4800 3050);
WIRE 16 -1 (4800 3050)(5200 3050);
WIRE 16 -1 (5200 3050)(5200 2900);
WIRE 16 -1 (5200 3050)(5600 3050);
WIRE 16 -1 (5600 2900)(5600 3050);
WIRE 16 -1 (5600 3050)(5975 3050);
WIRE 16 -1 (5975 2900)(5975 3050);
WIRE 16 -1 (6200 3050)(5975 3050);
WIRE 16 -1 (4400 2700)(4400 2550);
WIRE 16 -1 (4400 2550)(4800 2550);
WIRE 16 -1 (4800 2700)(4800 2550);
WIRE 16 -1 (5200 2550)(4800 2550);
WIRE 16 -1 (5200 2700)(5200 2550);
WIRE 16 -1 (5200 2550)(5600 2550);
WIRE 16 -1 (5600 2700)(5600 2550);
WIRE 16 -1 (5600 2550)(5975 2550);
WIRE 16 -1 (5975 2700)(5975 2550);
WIRE 16 -1 (6200 2550)(5975 2550);
WIRE 16 -1 (6425 1650)(6925 1650);
FORCEPROP 2 LAST SIG_NAME IND_P0_CPL1
J 0
(6515 1660);
DISPLAY 0.617021 (6515 1660);
WIRE 16 -1 (4950 2350)(5575 2350);
FORCEPROP 2 LAST SIG_NAME SW_PVCCIN_CPU0_BOOT6_R
J 0
(5240 2360);
DISPLAY 0.617021 (5240 2360);
WIRE 16 -1 (5575 2350)(5575 2275);
WIRE 16 -1 (4025 4175)(4275 4175);
WIRE 16 -1 (4025 4225)(4275 4225);
WIRE 16 -1 (4275 4225)(4275 4175);
WIRE 16 -1 (4275 4275)(4275 4225);
WIRE 16 -1 (4025 4275)(4275 4275);
WIRE 16 -1 (4000 2250)(4150 2250);
WIRE 16 -1 (4150 2250)(4150 2350);
FORCEPROP 2 LAST SIG_NAME SW_PVCCIN_CPU0_BOOT6
J 0
(3965 2360);
DISPLAY 0.617021 (3965 2360);
WIRE 16 -1 (4150 2350)(4750 2350);
WIRE 16 -1 (5050 1650)(5625 1650);
FORCEPROP 2 LAST SIG_NAME IND_P0_CPL6
J 0
(5140 1660);
DISPLAY 0.617021 (5140 1660);
WIRE 16 -1 (4000 2000)(5575 2000);
FORCEPROP 2 LAST SIG_NAME SW_PVCCIN_CPU0_BOOTR6
J 0
(4190 2010);
DISPLAY 0.617021 (4190 2010);
WIRE 16 -1 (5575 2000)(5575 2075);
WIRE 16 -1 (4000 1900)(5625 1900);
FORCEPROP 2 LAST SIG_NAME SW_PVCCIN_CPU0_SW6
J 0
(4190 1910);
DISPLAY 0.617021 (4190 1910);
WIRE 16 -1 (4000 1650)(4375 1650);
WIRE 16 -1 (4375 1650)(4375 1375);
WIRE 16 -1 (6025 1375)(4375 1375);
FORCEPROP 2 LAST SIG_NAME PVCCIN_CPU0_VOS6
J 0
(4590 1385);
DISPLAY 0.617021 (4590 1385);
WIRE 16 -1 (4000 1450)(4250 1450);
WIRE 16 -1 (4000 1400)(4250 1400);
WIRE 16 -1 (4250 1450)(4250 1400);
WIRE 16 -1 (4250 1400)(4250 1350);
WIRE 16 -1 (4000 1350)(4250 1350);
WIRE 16 -1 (2525 5950)(2525 5825);
WIRE 16 -1 (3100 5950)(2525 5950);
WIRE 16 -1 (3100 5375)(3100 5950);
WIRE 16 -1 (3175 5375)(3100 5375);
WIRE 16 -1 (2100 5475)(2100 5325);
WIRE 16 -1 (2100 5625)(2100 5475);
WIRE 16 -1 (2100 5475)(2500 5475);
WIRE 16 -1 (2500 5075)(2500 5475);
WIRE 16 -1 (2500 5075)(3075 5075);
FORCEPROP 2 LAST SIG_NAME PVCCIN_CPU0_VDD5
J 0
(2540 5085);
DISPLAY 0.617021 (2540 5085);
WIRE 16 -1 (3075 5075)(3175 5075);
WIRE 16 -1 (3075 4875)(3075 5075);
WIRE 16 -1 (3175 4875)(3075 4875);
WIRE 16 -1 (3075 4525)(2525 4525);
WIRE 16 -1 (2225 4625)(3075 4625);
FORCEPROP 2 LAST SIG_NAME PVCCIN_CPU0_VREF
J 0
(2340 4635);
DISPLAY 0.617021 (2340 4635);
WIRE 16 -1 (3075 4625)(3075 4525);
FORCEPROP 0 LAST CDS_PHYS_NET_NAME PVCCIN_CPU0_VREF
J 0
(3075 4550);
PAINT MONO (3075 4550);
DISPLAY INVISIBLE (3075 4550);
WIRE 16 -1 (3075 4625)(3175 4625);
WIRE 16 -1 (3175 4725)(2225 4725);
FORCEPROP 2 LAST SIG_NAME PVCCIN_CPU0_IMON5
J 0
(2340 4735);
DISPLAY 0.617021 (2340 4735);
WIRE 16 -1 (1700 4425)(1700 4325);
WIRE 16 -1 (1700 4425)(3175 4425);
FORCEPROP 2 LAST SIG_NAME PVCCIN_CPU0_LSET5
J 0
(2340 4435);
DISPLAY 0.617021 (2340 4435);
WIRE 16 -1 (2500 3125)(2500 3000);
WIRE 16 -1 (3075 3125)(2500 3125);
WIRE 16 -1 (3075 2550)(3075 3125);
WIRE 16 -1 (3150 2550)(3075 2550);
WIRE 16 -1 (3175 4125)(2225 4125);
FORCEPROP 2 LAST SIG_NAME PVCCIN_CPU0_PWM5
J 0
(2340 4135);
DISPLAY 0.617021 (2340 4135);
WIRE 16 -1 (3175 4225)(2225 4225);
FORCEPROP 2 LAST SIG_NAME PVCCIN_CPU0_ATSEN
J 0
(2340 4235);
DISPLAY 0.617021 (2340 4235);
WIRE 16 -1 (3150 2050)(3050 2050);
WIRE 16 -1 (3050 2050)(3050 2250);
WIRE 16 -1 (3150 2250)(3050 2250);
WIRE 16 -1 (3050 2250)(2475 2250);
FORCEPROP 2 LAST SIG_NAME PVCCIN_CPU0_VDD6
J 0
(2515 2260);
DISPLAY 0.617021 (2515 2260);
WIRE 16 -1 (2475 2250)(2475 2650);
WIRE 16 -1 (2075 2650)(2075 2500);
WIRE 16 -1 (2075 2800)(2075 2650);
WIRE 16 -1 (2075 2650)(2475 2650);
WIRE 16 -1 (3150 1900)(2200 1900);
FORCEPROP 2 LAST SIG_NAME PVCCIN_CPU0_IMON6
J 0
(2315 1910);
DISPLAY 0.617021 (2315 1910);
WIRE 16 -1 (3050 1700)(2500 1700);
WIRE 16 -1 (2200 1800)(3050 1800);
FORCEPROP 2 LAST SIG_NAME PVCCIN_CPU0_VREF
J 0
(2315 1810);
DISPLAY 0.617021 (2315 1810);
WIRE 16 -1 (3050 1800)(3050 1700);
FORCEPROP 0 LAST CDS_PHYS_NET_NAME PVCCIN_CPU0_VREF
J 0
(3050 1725);
PAINT MONO (3050 1725);
DISPLAY INVISIBLE (3050 1725);
WIRE 16 -1 (3050 1800)(3150 1800);
WIRE 16 -1 (3150 1400)(2200 1400);
FORCEPROP 2 LAST SIG_NAME PVCCIN_CPU0_ATSEN
J 0
(2315 1410);
DISPLAY 0.617021 (2315 1410);
WIRE 16 -1 (3150 1300)(2200 1300);
FORCEPROP 2 LAST SIG_NAME PVCCIN_CPU0_PWM6
J 0
(2315 1310);
DISPLAY 0.617021 (2315 1310);
WIRE 16 -1 (1675 1600)(1675 1500);
WIRE 16 -1 (1675 1600)(3150 1600);
FORCEPROP 2 LAST SIG_NAME PVCCIN_CPU0_LSET6
J 0
(2315 1610);
DISPLAY 0.617021 (2315 1610);
DOT 1 (3050 1800);
DOT 1 (3050 2250);
DOT 1 (2075 2650);
DOT 1 (2075 3125);
DOT 1 (2500 3125);
DOT 1 (2100 5475);
DOT 1 (2100 5950);
DOT 1 (2525 5950);
DOT 1 (3075 4625);
DOT 1 (3075 5075);
DOT 1 (4250 1350);
DOT 1 (4250 1300);
DOT 1 (4250 1400);
DOT 1 (4175 2550);
DOT 1 (4400 3050);
DOT 1 (4275 4125);
DOT 1 (4275 4175);
DOT 1 (4275 4225);
DOT 1 (4800 2550);
DOT 1 (5200 2550);
DOT 1 (4800 3050);
DOT 1 (5200 3050);
DOT 1 (5600 2550);
DOT 1 (5600 3050);
DOT 1 (7625 1900);
DOT 1 (7725 1900);
DOT 1 (5975 2550);
DOT 1 (5975 3050);
DOT 1 (4200 5375);
DOT 1 (4425 5875);
DOT 1 (4825 5375);
DOT 1 (5225 5375);
DOT 1 (5225 5875);
DOT 1 (4825 5875);
DOT 1 (5625 5375);
DOT 1 (5625 5875);
DOT 1 (6000 5375);
DOT 1 (6000 5875);
DOT 1 (7625 4725);
DOT 1 (8150 1475);
DOT 1 (8150 1900);
DOT 1 (8350 4300);
DOT 1 (7925 4725);
DOT 1 (8350 4725);
FORCENOTE
PVCCIN_CPU0_PHASE5
(3250 5900) 0;
DISPLAY LEFT (3250 5900);
DISPLAY 1.021277 (3250 5900);
PAINT WHITE (3250 5900);
FORCENOTE
PVCCIN_CPU0_PHASE6
(3200 3075) 0;
DISPLAY LEFT (3200 3075);
DISPLAY 1.021277 (3200 3075);
PAINT WHITE (3200 3075);
FORCENOTE
DCR=2-3,0.27M OHM
(6425 2050) 0;
DISPLAY LEFT (6425 2050);
DISPLAY 1.021277 (6425 2050);
FORCENOTE
DCR=1-4,0.105M OHM
(6425 2125) 0;
DISPLAY LEFT (6425 2125);
DISPLAY 1.021277 (6425 2125);
FORCENOTE
ISAT=70A@100C
(6425 2200) 0;
DISPLAY LEFT (6425 2200);
DISPLAY 1.021277 (6425 2200);
FORCENOTE
11.0*7.5*12.5
(6425 2275) 0;
DISPLAY LEFT (6425 2275);
DISPLAY 1.021277 (6425 2275);
FORCENOTE
PGL6303.151HLT 
(6425 2350) 0;
DISPLAY LEFT (6425 2350);
DISPLAY 1.021277 (6425 2350);
FORCENOTE
11.0*7.5*12.5
(6400 5075) 0;
DISPLAY LEFT (6400 5075);
DISPLAY 1.021277 (6400 5075);
FORCENOTE
ISAT=70A@100C
(6400 5000) 0;
DISPLAY LEFT (6400 5000);
DISPLAY 1.021277 (6400 5000);
FORCENOTE
DCR=1-4,0.105M OHM
(6400 4925) 0;
DISPLAY LEFT (6400 4925);
DISPLAY 1.021277 (6400 4925);
FORCENOTE
DCR=2-3,0.27M OHM
(6400 4850) 0;
DISPLAY LEFT (6400 4850);
DISPLAY 1.021277 (6400 4850);
FORCENOTE
PGL6303.151HLT 
(6400 5150) 0;
DISPLAY LEFT (6400 5150);
DISPLAY 1.021277 (6400 5150);
QUIT
